G04 ================== begin FILE IDENTIFICATION RECORD ==================*
G04 Layout Name:  14545-sa.brd*
G04 Film Name:    L2GND*
G04 File Format:  Gerber RS274X*
G04 File Origin:  Cadence Allegro 16.5-S056*
G04 Origin Date:  Fri Aug 01 17:58:40 2014*
G04 *
G04 Layer:  VIA CLASS/L2GND*
G04 Layer:  PIN/L2GND*
G04 Layer:  ETCH/L2GND*
G04 Layer:  DRAWING FORMAT/LAYER_PCB_STORY*
G04 Layer:  DRAWING FORMAT/LAYER_L2GND*
G04 *
G04 Offset:    (0.00 0.00)*
G04 Mirror:    No*
G04 Mode:      Negative*
G04 Rotation:  0*
G04 FullContactRelief:  No*
G04 UndefLineWidth:     6.00*
G04 ================== end FILE IDENTIFICATION RECORD ====================*
%FSLAX35Y35*MOIN*%
%IR0*IPPOS*OFA0.00000B0.00000*MIA0B0*SFA1.00000B1.00000*%
%AMMACRO19*
4,1,16,.07873,.05044,
.086293,.036002,
.091233,.020471,
.093402,.004317,
.092733,-.011967,
.089246,-.027888,
.083047,-.042962,
.07873,-.05044,
.08234,-.05406,
.090476,-.038941,
.095864,-.022638,
.098339,-.005647,
.097825,.011515,
.094339,.028327,
.087987,.044279,
.08234,.05406,
.07873,.05044,
0.0*
4,1,16,.05044,-.07873,
.036002,-.086293,
.020471,-.091233,
.004317,-.093402,
-.011967,-.092733,
-.027888,-.089246,
-.042962,-.083047,
-.05044,-.07873,
-.05406,-.08234,
-.038941,-.090476,
-.022638,-.095864,
-.005647,-.098339,
.011515,-.097825,
.028327,-.094339,
.044279,-.087987,
.05406,-.08234,
.05044,-.07873,
0.0*
4,1,16,-.07873,-.05044,
-.086293,-.036002,
-.091233,-.020471,
-.093402,-.004317,
-.092733,.011967,
-.089246,.027888,
-.083047,.042962,
-.07873,.05044,
-.08234,.05406,
-.090476,.038941,
-.095864,.022638,
-.098339,.005647,
-.097825,-.011515,
-.094339,-.028327,
-.087987,-.044279,
-.08234,-.05406,
-.07873,-.05044,
0.0*
4,1,16,-.05044,.07873,
-.036002,.086293,
-.020471,.091233,
-.004317,.093402,
.011967,.092733,
.027888,.089246,
.042962,.083047,
.05044,.07873,
.05406,.08234,
.038941,.090476,
.022638,.095864,
.005647,.098339,
-.011515,.097825,
-.028327,.094339,
-.044279,.087987,
-.05406,.08234,
-.05044,.07873,
0.0*
%
%ADD19MACRO19*%
%ADD15C,.032*%
%AMMACRO20*
4,1,20,-.01,-.05608,
-.015853,-.053819,
-.021224,-.050576,
-.025951,-.046449,
-.029889,-.041565,
-.032919,-.03607,
-.034949,-.030133,
-.035918,-.023934,
-.036,-.0215,
-.036,-.015,
-.031,-.015,
-.031,-.0215,
-.030529,-.026882,
-.029131,-.032101,
-.026847,-.036998,
-.023748,-.041424,
-.019928,-.045244,
-.015502,-.048343,
-.010605,-.050627,
-.01,-.05084,
-.01,-.05608,
90.*
4,1,20,.01,-.05608,
.01,-.05084,
.014943,-.048658,
.019432,-.045652,
.023331,-.041911,
.026521,-.03755,
.028905,-.032702,
.030411,-.027513,
.030993,-.022142,
.031,-.0215,
.031,-.015,
.036,-.015,
.036,-.0215,
.035453,-.027751,
.033829,-.033811,
.031177,-.039498,
.027579,-.044638,
.023142,-.049074,
.018002,-.052673,
.012316,-.055325,
.01,-.05608,
90.*
4,1,20,-.036,.015,
-.036,.0215,
-.035453,.027751,
-.033829,.033811,
-.031177,.039498,
-.027579,.044638,
-.023142,.049074,
-.018002,.052673,
-.012316,.055325,
-.01,.05608,
-.01,.05084,
-.014943,.048658,
-.019432,.045652,
-.023331,.041911,
-.026521,.03755,
-.028905,.032702,
-.030411,.027513,
-.030993,.022142,
-.031,.0215,
-.031,.015,
-.036,.015,
90.*
4,1,20,.031,.015,
.031,.0215,
.030529,.026882,
.029131,.032101,
.026847,.036998,
.023748,.041424,
.019928,.045244,
.015502,.048343,
.010605,.050627,
.01,.05084,
.01,.05608,
.015853,.053819,
.021224,.050576,
.025951,.046449,
.029889,.041565,
.032919,.03607,
.034949,.030133,
.035918,.023934,
.036,.0215,
.036,.015,
.031,.015,
90.*
%
%ADD20MACRO20*%
%ADD14C,.036*%
%AMMACRO22*
4,1,15,.00398,.00044,
.003999,.000208,
.004004,-.000025,
.003996,-.000258,
.00398,-.00044,
.00483,-.00129,
.004897,-.001007,
.004947,-.000721,
.004981,-.000432,
.004997,-.000141,
.004997,.000149,
.00498,.00044,
.004946,.000729,
.004895,.001015,
.00483,.00129,
.00398,.00044,
90.*
4,1,15,.00044,-.00398,
.000208,-.003999,
-.000025,-.004004,
-.000258,-.003996,
-.00044,-.00398,
-.00129,-.00483,
-.001007,-.004897,
-.000721,-.004947,
-.000432,-.004981,
-.000141,-.004997,
.000149,-.004997,
.00044,-.00498,
.000729,-.004946,
.001015,-.004895,
.00129,-.00483,
.00044,-.00398,
90.*
4,1,15,-.00398,-.00044,
-.003999,-.000208,
-.004004,.000025,
-.003996,.000258,
-.00398,.00044,
-.00483,.00129,
-.004897,.001007,
-.004947,.000721,
-.004981,.000432,
-.004997,.000141,
-.004997,-.000149,
-.00498,-.00044,
-.004946,-.000729,
-.004895,-.001015,
-.00483,-.00129,
-.00398,-.00044,
90.*
4,1,15,-.00044,.00398,
-.000208,.003999,
.000025,.004004,
.000258,.003996,
.00044,.00398,
.00129,.00483,
.001007,.004897,
.000721,.004947,
.000432,.004981,
.000141,.004997,
-.000149,.004997,
-.00044,.00498,
-.000729,.004946,
-.001015,.004895,
-.00129,.00483,
-.00044,.00398,
90.*
%
%ADD22MACRO22*%
%AMMACRO13*
4,1,15,.00398,.00044,
.003999,.000208,
.004004,-.000025,
.003996,-.000258,
.00398,-.00044,
.00483,-.00129,
.004897,-.001007,
.004947,-.000721,
.004981,-.000432,
.004997,-.000141,
.004997,.000149,
.00498,.00044,
.004946,.000729,
.004895,.001015,
.00483,.00129,
.00398,.00044,
0.0*
4,1,15,.00044,-.00398,
.000208,-.003999,
-.000025,-.004004,
-.000258,-.003996,
-.00044,-.00398,
-.00129,-.00483,
-.001007,-.004897,
-.000721,-.004947,
-.000432,-.004981,
-.000141,-.004997,
.000149,-.004997,
.00044,-.00498,
.000729,-.004946,
.001015,-.004895,
.00129,-.00483,
.00044,-.00398,
0.0*
4,1,15,-.00398,-.00044,
-.003999,-.000208,
-.004004,.000025,
-.003996,.000258,
-.00398,.00044,
-.00483,.00129,
-.004897,.001007,
-.004947,.000721,
-.004981,.000432,
-.004997,.000141,
-.004997,-.000149,
-.00498,-.00044,
-.004946,-.000729,
-.004895,-.001015,
-.00483,-.00129,
-.00398,-.00044,
0.0*
4,1,15,-.00044,.00398,
-.000208,.003999,
.000025,.004004,
.000258,.003996,
.00044,.00398,
.00129,.00483,
.001007,.004897,
.000721,.004947,
.000432,.004981,
.000141,.004997,
-.000149,.004997,
-.00044,.00498,
-.000729,.004946,
-.001015,.004895,
-.00129,.00483,
-.00044,.00398,
0.0*
%
%ADD13MACRO13*%
%ADD18C,.101*%
%ADD10C,.114*%
%AMMACRO17*
4,1,20,-.01,-.05608,
-.015853,-.053819,
-.021224,-.050576,
-.025951,-.046449,
-.029889,-.041565,
-.032919,-.03607,
-.034949,-.030133,
-.035918,-.023934,
-.036,-.0215,
-.036,-.015,
-.031,-.015,
-.031,-.0215,
-.030529,-.026882,
-.029131,-.032101,
-.026847,-.036998,
-.023748,-.041424,
-.019928,-.045244,
-.015502,-.048343,
-.010605,-.050627,
-.01,-.05084,
-.01,-.05608,
270.*
4,1,20,.01,-.05608,
.01,-.05084,
.014943,-.048658,
.019432,-.045652,
.023331,-.041911,
.026521,-.03755,
.028905,-.032702,
.030411,-.027513,
.030993,-.022142,
.031,-.0215,
.031,-.015,
.036,-.015,
.036,-.0215,
.035453,-.027751,
.033829,-.033811,
.031177,-.039498,
.027579,-.044638,
.023142,-.049074,
.018002,-.052673,
.012316,-.055325,
.01,-.05608,
270.*
4,1,20,-.036,.015,
-.036,.0215,
-.035453,.027751,
-.033829,.033811,
-.031177,.039498,
-.027579,.044638,
-.023142,.049074,
-.018002,.052673,
-.012316,.055325,
-.01,.05608,
-.01,.05084,
-.014943,.048658,
-.019432,.045652,
-.023331,.041911,
-.026521,.03755,
-.028905,.032702,
-.030411,.027513,
-.030993,.022142,
-.031,.0215,
-.031,.015,
-.036,.015,
270.*
4,1,20,.031,.015,
.031,.0215,
.030529,.026882,
.029131,.032101,
.026847,.036998,
.023748,.041424,
.019928,.045244,
.015502,.048343,
.010605,.050627,
.01,.05084,
.01,.05608,
.015853,.053819,
.021224,.050576,
.025951,.046449,
.029889,.041565,
.032919,.03607,
.034949,.030133,
.035918,.023934,
.036,.0215,
.036,.015,
.031,.015,
270.*
%
%ADD17MACRO17*%
%ADD12C,.119*%
%ADD23C,.174*%
%AMMACRO21*
4,1,15,.00398,.00044,
.003999,.000208,
.004004,-.000025,
.003996,-.000258,
.00398,-.00044,
.00483,-.00129,
.004897,-.001007,
.004947,-.000721,
.004981,-.000432,
.004997,-.000141,
.004997,.000149,
.00498,.00044,
.004946,.000729,
.004895,.001015,
.00483,.00129,
.00398,.00044,
180.*
4,1,15,.00044,-.00398,
.000208,-.003999,
-.000025,-.004004,
-.000258,-.003996,
-.00044,-.00398,
-.00129,-.00483,
-.001007,-.004897,
-.000721,-.004947,
-.000432,-.004981,
-.000141,-.004997,
.000149,-.004997,
.00044,-.00498,
.000729,-.004946,
.001015,-.004895,
.00129,-.00483,
.00044,-.00398,
180.*
4,1,15,-.00398,-.00044,
-.003999,-.000208,
-.004004,.000025,
-.003996,.000258,
-.00398,.00044,
-.00483,.00129,
-.004897,.001007,
-.004947,.000721,
-.004981,.000432,
-.004997,.000141,
-.004997,-.000149,
-.00498,-.00044,
-.004946,-.000729,
-.004895,-.001015,
-.00483,-.00129,
-.00398,-.00044,
180.*
4,1,15,-.00044,.00398,
-.000208,.003999,
.000025,.004004,
.000258,.003996,
.00044,.00398,
.00129,.00483,
.001007,.004897,
.000721,.004947,
.000432,.004981,
.000141,.004997,
-.000149,.004997,
-.00044,.00498,
-.000729,.004946,
-.001015,.004895,
-.00129,.00483,
-.00044,.00398,
180.*
%
%ADD21MACRO21*%
%AMMACRO11*
4,1,15,.00398,.00044,
.003999,.000208,
.004004,-.000025,
.003996,-.000258,
.00398,-.00044,
.00483,-.00129,
.004897,-.001007,
.004947,-.000721,
.004981,-.000432,
.004997,-.000141,
.004997,.000149,
.00498,.00044,
.004946,.000729,
.004895,.001015,
.00483,.00129,
.00398,.00044,
270.*
4,1,15,.00044,-.00398,
.000208,-.003999,
-.000025,-.004004,
-.000258,-.003996,
-.00044,-.00398,
-.00129,-.00483,
-.001007,-.004897,
-.000721,-.004947,
-.000432,-.004981,
-.000141,-.004997,
.000149,-.004997,
.00044,-.00498,
.000729,-.004946,
.001015,-.004895,
.00129,-.00483,
.00044,-.00398,
270.*
4,1,15,-.00398,-.00044,
-.003999,-.000208,
-.004004,.000025,
-.003996,.000258,
-.00398,.00044,
-.00483,.00129,
-.004897,.001007,
-.004947,.000721,
-.004981,.000432,
-.004997,.000141,
-.004997,-.000149,
-.00498,-.00044,
-.004946,-.000729,
-.004895,-.001015,
-.00483,-.00129,
-.00398,-.00044,
270.*
4,1,15,-.00044,.00398,
-.000208,.003999,
.000025,.004004,
.000258,.003996,
.00044,.00398,
.00129,.00483,
.001007,.004897,
.000721,.004947,
.000432,.004981,
.000141,.004997,
-.000149,.004997,
-.00044,.00498,
-.000729,.004946,
-.001015,.004895,
-.00129,.00483,
-.00044,.00398,
270.*
%
%ADD11MACRO11*%
%AMMACRO16*
4,1,16,.07256,.04427,
.079145,.030998,
.083325,.016783,
.084974,.002059,
.08404,-.012728,
.080553,-.027128,
.074619,-.040704,
.07256,-.04427,
.07619,-.04791,
.083352,-.033952,
.087981,-.018962,
.089937,-.003396,
.089161,.012273,
.085675,.027569,
.079586,.042027,
.07619,.04791,
.07256,.04427,
0.0*
4,1,16,.04427,-.07256,
.030998,-.079145,
.016783,-.083325,
.002059,-.084974,
-.012728,-.08404,
-.027128,-.080553,
-.040704,-.074619,
-.04427,-.07256,
-.04791,-.07619,
-.033952,-.083352,
-.018962,-.087981,
-.003396,-.089937,
.012273,-.089161,
.027569,-.085675,
.042027,-.079586,
.04791,-.07619,
.04427,-.07256,
0.0*
4,1,16,-.07256,-.04427,
-.079145,-.030998,
-.083325,-.016783,
-.084974,-.002059,
-.08404,.012728,
-.080553,.027128,
-.074619,.040704,
-.07256,.04427,
-.07619,.04791,
-.083352,.033952,
-.087981,.018962,
-.089937,.003396,
-.089161,-.012273,
-.085675,-.027569,
-.079586,-.042027,
-.07619,-.04791,
-.07256,-.04427,
0.0*
4,1,16,-.04427,.07256,
-.030998,.079145,
-.016783,.083325,
-.002059,.084974,
.012728,.08404,
.027128,.080553,
.040704,.074619,
.04427,.07256,
.04791,.07619,
.033952,.083352,
.018962,.087981,
.003396,.089937,
-.012273,.089161,
-.027569,.085675,
-.042027,.079586,
-.04791,.07619,
-.04427,.07256,
0.0*
%
%ADD16MACRO16*%
%ADD24C,.02*%
%ADD25C,.006*%
%ADD34R,.142X.028*%
%ADD30C,.09704*%
%ADD32R,.075X.02*%
%ADD29C,.11504*%
%ADD26O,.0802X.0462*%
%ADD31C,.17004*%
%ADD28O,.0812X.0462*%
%ADD33R,.094X.026*%
%ADD27O,.0822X.0462*%
%ADD35R,.07509X.0691*%
G75*
%LPD*%
G75*
G36*
G01X-6000Y-6000D02*
X1039465D01*
Y1998126D01*
X-6000D01*
Y-6000D01*
G37*
%LPC*%
G75*
G36*
G01X3937Y3004D02*
G02X3004Y3937I0J933D01*
G01Y210369D01*
X3214Y210579D01*
X19882D01*
G03Y224067I0J6744D01*
G01X3213D01*
X3004Y224276D01*
Y410369D01*
X3214Y410579D01*
X19882D01*
G03X25866Y420434I0J6744D01*
G02X26247Y421018I355J185D01*
G03X28694Y423060I152J2304D01*
G01X28714Y423237D01*
X28717D01*
X28842Y426635D01*
X28840D01*
X28831Y426826D01*
G03X24221Y426887I-2307J-106D01*
G01X24215Y426813D01*
X24206Y426804D01*
X24081Y423407D01*
X24083D01*
X24092Y423216D01*
G03X24111Y423005I2307J101D01*
G02X23797Y422814I-198J-28D01*
G03X19883Y424067I-3915J-5491D01*
G01X19668D01*
Y424628D01*
X5468D01*
Y424067D01*
X3213D01*
X3004Y424276D01*
Y819818D01*
X3213Y820027D01*
X19882D01*
G03Y833516I0J6745D01*
G01X3213D01*
X3004Y833725D01*
Y1194621D01*
X3214Y1194831D01*
X19882D01*
G03Y1208319I0J6744D01*
G01X3213D01*
X3004Y1208528D01*
Y1394621D01*
X3214Y1394831D01*
X19882D01*
G03Y1408319I0J6744D01*
G01X19668D01*
Y1408880D01*
X5468D01*
Y1408319D01*
X3213D01*
X3004Y1408528D01*
Y1804070D01*
X3213Y1804279D01*
X19882D01*
G03Y1817768I0J6744D01*
G01X3213D01*
X3004Y1817977D01*
Y1988189D01*
G02X3937Y1989122I933J0D01*
G01X1029528D01*
G02X1030461Y1988189I0J-933D01*
G01Y1686599D01*
X1028283Y1684421D01*
X1024211D01*
G03X1016287Y1676496I1J-7925D01*
G01Y1621265D01*
X1014109Y1619087D01*
X989744D01*
G03Y1608866I0J-5110D01*
G01X1014109D01*
X1016287Y1606688D01*
Y1433740D01*
G03X1024211Y1425815I7925J0D01*
G01X1028283D01*
X1030461Y1423637D01*
Y3937D01*
G02X1029528Y3004I-933J0D01*
G01X3937D01*
G37*
%LPD*%
G75*
G36*
G01X853512Y1873346D02*
G02X853485Y1868726I-14J-2310D01*
G01X850085Y1868746D01*
G02X850113Y1873366I14J2310D01*
G01X853512Y1873346D01*
G37*
G36*
G01X121083Y1870817D02*
X121080Y1870995D01*
X121077D01*
X121276Y1874390D01*
X121278D01*
X121305Y1874580D01*
G02X125902Y1874296I2287J-325D01*
G01X125905Y1874118D01*
X125908D01*
X125709Y1870724D01*
X125700Y1870715D01*
X125693Y1870643D01*
G02X121083Y1870817I-2300J216D01*
G37*
G36*
G01X869224Y1861839D02*
G02X864604Y1861840I-2310J1D01*
G01Y1865615D01*
G02X869224I2310J0D01*
G01Y1861839D01*
G37*
G36*
G01X140309Y1861496D02*
G02X135689Y1861497I-2310J1D01*
G01Y1865151D01*
G02X140309I2310J0D01*
G01Y1861496D01*
G37*
G36*
G01X82886Y1748948D02*
X83033Y1752344D01*
G02X87649Y1752145I2308J-99D01*
G01X87502Y1748748D01*
G02X82886Y1748948I-2308J100D01*
G37*
G36*
G01X107570Y1738136D02*
X107277D01*
Y1737851D01*
X99768D01*
Y1744761D01*
X107532D01*
G02X111805Y1743681I1967J-1211D01*
G01X111816Y1743492D01*
X111818D01*
X111718Y1739492D01*
X111715D01*
X111696Y1739313D01*
G02X107630Y1738065I-2297J237D01*
G01X107570Y1738136D01*
G37*
G36*
G01X48187Y1724823D02*
G02X43567I-2310J0D01*
G01Y1728478D01*
G02X48187Y1728477I2310J-1D01*
G01Y1724823D01*
G37*
G36*
G01X29660Y1642692D02*
G02X29593Y1647312I-34J2310D01*
G01X32993Y1647361D01*
G02X33059Y1642741I33J-2310D01*
G01X29660Y1642692D01*
G37*
G36*
G01X30219Y1509592D02*
G02X30012Y1514208I-104J2308D01*
G01X33409Y1514359D01*
G02X33615Y1509743I103J-2308D01*
G01X30219Y1509592D01*
G37*
G36*
G01X852326Y1468656D02*
G02X852250Y1464036I-38J-2310D01*
G01X848851Y1464092D01*
G02X848926Y1468712I38J2310D01*
G01X852326Y1468656D01*
G37*
G36*
G01X30485Y1460210D02*
G02X30272Y1464826I-106J2308D01*
G01X33809Y1464989D01*
G02X34021Y1460373I106J-2308D01*
G01X30485Y1460210D01*
G37*
G36*
G01X875767Y1456129D02*
X875740Y1456319D01*
X875738D01*
X875537Y1459860D01*
X875540D01*
X875544Y1460038D01*
G02X880159Y1460121I2309J-48D01*
G01X880170Y1459922D01*
X880180D01*
X880370Y1456582D01*
X880362Y1456574D01*
X880363Y1456489D01*
G02X875767Y1456129I-2309J-39D01*
G37*
G36*
G01X140702Y1456131D02*
X140683Y1456310D01*
X140680D01*
X140581Y1459937D01*
X140583D01*
X140594Y1460126D01*
G02X145197Y1460242I2306J-127D01*
G01X145216Y1460063D01*
X145219D01*
X145318Y1456437D01*
X145310Y1456429D01*
X145309Y1456347D01*
G02X140702Y1456131I-2310J26D01*
G37*
G36*
G01X107245Y1440601D02*
G02X102625Y1440668I-2310J33D01*
G01X102689Y1444975D01*
G02X107309Y1444907I2310J-34D01*
G01X107245Y1440601D01*
G37*
G36*
G01X31903Y1430445D02*
X31745Y1430553D01*
X31744Y1430551D01*
X29037Y1432749D01*
X29039Y1432752D01*
X28910Y1432874D01*
G02X31955Y1436343I1590J1676D01*
G01X32110Y1436217D01*
X32116Y1436225D01*
X34668Y1434154D01*
Y1434142D01*
X34736Y1434083D01*
G02X31903Y1430445I-1529J-1732D01*
G37*
G36*
G01X119700Y1426200D02*
G02X115080Y1426201I-2310J1D01*
G01Y1429976D01*
G02X119700I2310J0D01*
G01Y1426200D01*
G37*
G36*
G01X31582Y1387198D02*
X31409Y1387257D01*
X31408Y1387255D01*
X27575Y1388922D01*
X27555Y1388942D01*
X27523Y1388957D01*
G02X29250Y1393235I977J2093D01*
G01X29423Y1393176D01*
X29424Y1393178D01*
X33258Y1391511D01*
X33257Y1391509D01*
X33421Y1391421D01*
G02X31582Y1387198I-1089J-2038D01*
G37*
G36*
G01X99536Y1373462D02*
G02X94922Y1373213I-2307J-125D01*
G01X94693Y1377476D01*
G02X99307Y1377724I2307J124D01*
G01X99536Y1373462D01*
G37*
G36*
G01X114719Y1357817D02*
G02X110161Y1358576I-2279J380D01*
G01X110720Y1361930D01*
G02X115278Y1361170I2279J-380D01*
G01X114719Y1357817D01*
G37*
G36*
G01X104017Y1342901D02*
G02X100040Y1344500I-1667J1599D01*
G01Y1348154D01*
G02X103959Y1349811I2310J0D01*
G01X111228D01*
Y1349371D01*
X111534D01*
X111593Y1349458D01*
G02X115810Y1348154I1907J-1304D01*
G01Y1344499D01*
G02X111593Y1343196I-2310J1D01*
G01X111534Y1343284D01*
X111228D01*
Y1342901D01*
X104017D01*
G37*
G36*
G01X111538Y1333315D02*
G02X106918I-2310J0D01*
G01Y1337091D01*
G02X111538Y1337090I2310J-1D01*
G01Y1333315D01*
G37*
G36*
G01X139791Y1077561D02*
G02X135171Y1077554I-2310J-3D01*
G01X135167Y1081174D01*
G02X139787Y1081180I2310J3D01*
G01Y1081174D01*
X139791Y1077561D01*
G37*
G36*
G01X126733Y1077522D02*
G02X122113Y1077523I-2310J1D01*
G01Y1081177D01*
G02X126733I2310J0D01*
G01Y1077522D01*
G37*
G36*
G01X850865Y1063751D02*
G02X850800Y1059131I-32J-2310D01*
G01X847200Y1059182D01*
G02X847266Y1063802I33J2310D01*
G01X850865Y1063751D01*
G37*
G36*
G01X880536Y1051279D02*
G02X875930Y1050912I-2303J-183D01*
G01X875661Y1054302D01*
G02X880267Y1054668I2303J183D01*
G01X880536Y1051279D01*
G37*
G36*
G01X126309Y1050650D02*
G02X121689I-2310J0D01*
G01Y1054051D01*
G02X126309Y1054050I2310J-1D01*
G01Y1050650D01*
G37*
G36*
G01X88693Y937322D02*
G02X84105Y936778I-2294J-272D01*
G01X83705Y940156D01*
G02X88293Y940701I2294J272D01*
G01X88693Y937322D01*
G37*
G36*
G01X111403Y928423D02*
G02X106795Y928078I-2304J-173D01*
G01X106541Y931485D01*
G02X111149Y931829I2304J172D01*
G01X111403Y928423D01*
G37*
G36*
G01X29997Y667446D02*
G02X25377Y667447I-2310J1D01*
G01Y671101D01*
G02X29997I2310J0D01*
G01Y667446D01*
G37*
G36*
G01X847814Y653060D02*
G02X847730Y657680I-42J2310D01*
G01X851129Y657742D01*
G02X851214Y653122I42J-2310D01*
G01X847814Y653060D01*
G37*
G36*
G01X880906Y645572D02*
G02X876286Y645573I-2310J1D01*
G01Y649348D01*
G02X880906I2310J0D01*
G01Y645572D01*
G37*
G36*
G01X146548Y645355D02*
G02X141928Y645356I-2310J1D01*
G01Y649131D01*
G02X146548I2310J0D01*
G01Y645355D01*
G37*
G36*
G01X132021Y646825D02*
G02X130779Y642375I-621J-2225D01*
G01X127409Y643317D01*
X127408D01*
G02X128620Y647775I591J2233D01*
G01X132021Y646825D01*
G37*
G36*
G01X127809Y635549D02*
G02X123189Y635550I-2310J1D01*
G01Y638950D01*
G02X127809I2310J0D01*
G01Y635549D01*
G37*
G36*
G01X57689Y537547D02*
G02X62309Y537553I2310J3D01*
G01Y537547D01*
X62313Y534154D01*
G02X57693Y534147I-2310J-3D01*
G01X57689Y537547D01*
G37*
G36*
G01X88509Y532249D02*
G02X83889Y532250I-2310J1D01*
G01Y536025D01*
G02X88509I2310J0D01*
G01Y532249D01*
G37*
G36*
G01X28909Y525647D02*
G02X24289Y525648I-2310J1D01*
G01Y529302D01*
G02X28909I2310J0D01*
G01Y525647D01*
G37*
G36*
G01X38809Y517774D02*
G02X34189Y517775I-2310J1D01*
G01Y521550D01*
G02X38809I2310J0D01*
G01Y517774D01*
G37*
G36*
G01X28709Y501965D02*
G02X24089Y501966I-2310J1D01*
G01Y505741D01*
G02X28709I2310J0D01*
G01Y501965D01*
G37*
G36*
G01X62291Y486368D02*
X62391Y489768D01*
G02X67009Y489632I2309J-68D01*
G01X66909Y486244D01*
G02X62291Y486368I-2309J56D01*
G37*
G36*
G01X23990Y478372D02*
X23987Y478551D01*
X23984D01*
X24200Y481945D01*
X24202D01*
X24230Y482134D01*
G02X28824Y481830I2285J-337D01*
G01X28827Y481651D01*
X28830D01*
X28614Y478258D01*
X28604Y478248D01*
X28597Y478177D01*
G02X23990Y478372I-2298J227D01*
G37*
G36*
G01X62087Y474442D02*
G02X66707Y474450I2310J4D01*
G01Y474442D01*
X66713Y471051D01*
G02X62093Y471042I-2310J-5D01*
G01X62087Y474442D01*
G37*
G36*
G01X25191Y460155D02*
G03X25145Y460767I-279J287D01*
G02X24176Y462656I1341J1881D01*
G01X24189Y466258D01*
G02X28809Y466242I2310J-8D01*
G01X28796Y462641D01*
G02X28094Y460990I-2310J7D01*
G03X28140Y460378I279J-287D01*
G02X29096Y458740I-1341J-1881D01*
G01X29115Y458561D01*
X29118D01*
X29218Y454915D01*
X29210Y454907D01*
X29209Y454825D01*
G02X24602Y454607I-2310J24D01*
G01X24583Y454786D01*
X24580D01*
X24480Y458433D01*
X24482D01*
X24493Y458622D01*
G02X25191Y460155I2306J-125D01*
G37*
G36*
G01X28801Y439278D02*
G02X24183Y439423I-2309J73D01*
G01X24290Y442822D01*
G02X28908Y442676I2309J-73D01*
G01X28801Y439278D01*
G37*
G36*
G01X28609Y399600D02*
G02X23989Y399601I-2310J1D01*
G01Y403376D01*
G02X28609I2310J0D01*
G01Y399600D01*
G37*
G36*
G01Y383853D02*
G02X23989Y383854I-2310J1D01*
G01Y387629D01*
G02X28609I2310J0D01*
G01Y383853D01*
G37*
G36*
G01X120532Y248709D02*
X120497Y248888D01*
X120494D01*
X120092Y252425D01*
X120100Y252433D01*
X120093Y252524D01*
G02X124664Y253129I2304J163D01*
G01X124699Y252950D01*
X124702D01*
X125104Y249412D01*
X125102D01*
X125108Y249225D01*
G02X120532Y248709I-2309J-75D01*
G37*
G36*
G01X880388Y240102D02*
G02X875768Y240103I-2310J1D01*
G01Y243878D01*
G02X880388I2310J0D01*
G01Y240102D01*
G37*
G36*
G01X152309Y239728D02*
G02X147689Y239729I-2310J1D01*
G01Y243504D01*
G02X152309I2310J0D01*
G01Y239728D01*
G37*
G36*
G01X88902Y126569D02*
G02X84296Y126931I-2303J181D01*
G01X84596Y130747D01*
G02X89202Y130386I2303J-181D01*
G01X88902Y126569D01*
G37*
G36*
G01X29831Y1671683D02*
X29868Y1671670D01*
X31469Y1671768D01*
X31504Y1671784D01*
G02X31763Y1667523I990J-2078D01*
G01X31726Y1667536D01*
X30125Y1667438D01*
X30090Y1667422D01*
G02X29831Y1671683I-990J2078D01*
G37*
G36*
G01X29128Y1663280D02*
X29153Y1663274D01*
X31331Y1663330D01*
X31356Y1663337D01*
G02X31471Y1658886I643J-2210D01*
G01X31446Y1658892D01*
X29268Y1658836D01*
X29243Y1658829D01*
G02X29128Y1663280I-643J2210D01*
G37*
G36*
G01X30984Y1626606D02*
X28932Y1627819D01*
X28906Y1627826D01*
G02X31159Y1631645I593J2224D01*
G01X31178Y1631625D01*
X33232Y1630412D01*
X33259Y1630405D01*
G02X31003Y1626586I-596J-2224D01*
G01X30984Y1626606D01*
G37*
G36*
G01X31654Y1611314D02*
X29544D01*
X29518Y1611307D01*
G02Y1615741I-619J2217D01*
G01X29544Y1615734D01*
X31654D01*
X31680Y1615741D01*
G02Y1611307I619J-2217D01*
G01X31654Y1611314D01*
G37*
G36*
G01X30330Y1569755D02*
X27102Y1569903D01*
X27099D01*
G02X27310Y1574499I23J2302D01*
G01X27313D01*
X30540Y1574351D01*
X30543D01*
G02X30333Y1569755I-22J-2302D01*
G01X30330D01*
G37*
G36*
G01X29782Y1518465D02*
X29789Y1518491D01*
Y1520855D01*
X29782Y1520881D01*
G02X34216I2217J619D01*
G01X34209Y1520855D01*
Y1518491D01*
X34216Y1518465D01*
G02X29782I-2217J-619D01*
G37*
G36*
G01X33348Y1479670D02*
X31669Y1479847D01*
X31632Y1479837D01*
G02X32081Y1484082I-633J2213D01*
G01X32116Y1484063D01*
X33794Y1483886D01*
X33832Y1483896D01*
G02X33383Y1479651I633J-2213D01*
G01X33348Y1479670D01*
G37*
G36*
G01X121786Y1466151D02*
X121805Y1466185D01*
X122081Y1468591D01*
X122071Y1468628D01*
G02X125830Y1470952I2219J613D01*
G01X133168D01*
Y1464042D01*
X125878D01*
G02X121786Y1466151I-2070J1008D01*
G37*
G36*
G01X29485Y1450459D02*
X29523Y1450445D01*
X31080Y1450515D01*
X31116Y1450532D01*
G02X31306Y1446285I978J-2084D01*
G01X31268Y1446299D01*
X29711Y1446229D01*
X29675Y1446212D01*
G02X29485Y1450459I-978J2084D01*
G37*
G36*
G01X29054Y1413851D02*
Y1413859D01*
X32505Y1413777D01*
X32512Y1413770D01*
X32587Y1413766D01*
G02X32396Y1409167I-136J-2298D01*
G01Y1409159D01*
X28944Y1409241D01*
Y1409242D01*
X28764Y1409260D01*
G02X29054Y1413851I236J2290D01*
G37*
G36*
G01X27808Y1371991D02*
Y1371987D01*
X27857Y1368569D01*
Y1368566D01*
G02X23257Y1368501I-2299J-120D01*
G01Y1368505D01*
X23208Y1371922D01*
Y1371926D01*
G02X27808Y1371991I2299J120D01*
G37*
G36*
G01X89190Y1346539D02*
Y1342952D01*
G02X84590I-2300J-92D01*
G01Y1346543D01*
G02X89190I2300J92D01*
G01Y1346539D01*
G37*
G36*
G01X52602Y699187D02*
Y699183D01*
X52706Y695966D01*
Y695962D01*
G02X48108Y695814I-2296J-161D01*
G01Y695818D01*
X48004Y699034D01*
Y699038D01*
G02X52602Y699187I2296J163D01*
G37*
G36*
G01X24435Y651912D02*
X24432Y652089D01*
X24431D01*
X24693Y656685D01*
X24720Y656872D01*
G02X29301Y656595I2279J-322D01*
G01X29304Y656418D01*
X29305D01*
X29043Y651826D01*
X29042D01*
X29019Y651652D01*
G02X24435Y651912I-2282J305D01*
G37*
G36*
G01X28868Y639508D02*
Y636042D01*
G02X24268I-2300J-92D01*
G01Y639512D01*
G02X28868I2300J92D01*
G01Y639508D01*
G37*
G36*
G01X29799Y623761D02*
Y620295D01*
G02X25199I-2300J-92D01*
G01Y623765D01*
G02X29799I2300J92D01*
G01Y623761D01*
G37*
G36*
G01X117986Y129129D02*
Y126894D01*
X118001Y126857D01*
G02X113751I-2125J-884D01*
G01X113766Y126894D01*
Y129129D01*
X113751Y129166D01*
G02X118001I2125J884D01*
G01X117986Y129129D01*
G37*
G36*
G01X853042Y248482D02*
G02X851233Y247664I-1764J1492D01*
G01X847834Y247730D01*
G02X847923Y252350I44J2310D01*
G01X850092Y252308D01*
G03X850500Y252708I8J400D01*
G01Y254300D01*
X850835Y254635D01*
X861256D01*
Y247725D01*
X853747D01*
Y248224D01*
G03X853042Y248482I-400J-1D01*
G37*
G54D34*
X12568Y383857D03*
Y387794D03*
Y399605D03*
Y403542D03*
Y427165D03*
Y438977D03*
Y442914D03*
Y454725D03*
Y458662D03*
Y470473D03*
Y474410D03*
Y486221D03*
Y490158D03*
Y501969D03*
Y505906D03*
Y517717D03*
Y521654D03*
Y533465D03*
Y537402D03*
Y568898D03*
Y572835D03*
Y620079D03*
Y624016D03*
Y635827D03*
Y639764D03*
Y651575D03*
Y655512D03*
Y667323D03*
Y671260D03*
Y1368109D03*
Y1372046D03*
Y1383857D03*
Y1387794D03*
Y1411417D03*
Y1423229D03*
Y1427166D03*
Y1438977D03*
Y1442914D03*
Y1454725D03*
Y1458662D03*
Y1470473D03*
Y1474410D03*
Y1486221D03*
Y1490158D03*
Y1501969D03*
Y1505906D03*
Y1517717D03*
Y1521654D03*
Y1553150D03*
Y1557087D03*
Y1604331D03*
Y1608268D03*
Y1620079D03*
Y1624016D03*
Y1635827D03*
Y1639764D03*
Y1651575D03*
Y1655512D03*
Y1667323D03*
Y1671260D03*
G54D30*
X78150Y28858D03*
Y178464D03*
Y434370D03*
Y583976D03*
Y839882D03*
Y989488D03*
Y1245394D03*
Y1395000D03*
Y1650906D03*
Y1800512D03*
X158071Y191614D03*
Y341220D03*
Y597126D03*
Y746732D03*
Y1002638D03*
Y1152244D03*
Y1408150D03*
Y1557756D03*
Y1813662D03*
Y1963268D03*
X886417Y191614D03*
Y341220D03*
Y597126D03*
Y746732D03*
Y1002638D03*
Y1152244D03*
Y1408150D03*
Y1557756D03*
Y1813662D03*
Y1963268D03*
G54D32*
X77165Y117349D03*
Y120498D03*
Y126798D03*
Y129947D03*
X159054Y240105D03*
X887400D03*
X159054Y243254D03*
X887400D03*
X159054Y249554D03*
X887400D03*
X159054Y252703D03*
X887400D03*
X77165Y522861D03*
Y526010D03*
Y532310D03*
Y535459D03*
X159054Y645617D03*
X887400D03*
X159054Y648766D03*
X887400D03*
X159054Y655066D03*
X887400D03*
X159054Y658215D03*
X887400D03*
X77165Y928373D03*
Y931522D03*
Y937822D03*
Y940971D03*
X159054Y1051129D03*
X887400D03*
X159054Y1054278D03*
X887400D03*
X159054Y1060578D03*
X887400D03*
X159054Y1063727D03*
X887400D03*
X77165Y1333885D03*
Y1337034D03*
Y1343334D03*
Y1346483D03*
X159054Y1456641D03*
X887400D03*
X159054Y1459790D03*
X887400D03*
X159054Y1466090D03*
X887400D03*
X159054Y1469239D03*
X887400D03*
X77165Y1739397D03*
Y1742546D03*
Y1748846D03*
Y1751995D03*
X159054Y1862153D03*
X887400D03*
X159054Y1865302D03*
X887400D03*
X159054Y1871602D03*
X887400D03*
X159054Y1874751D03*
X887400D03*
G54D29*
X9843Y153168D03*
Y265767D03*
Y353144D03*
Y717711D03*
Y762617D03*
Y875216D03*
Y1137420D03*
Y1250019D03*
Y1337396D03*
Y1701963D03*
Y1746869D03*
Y1859468D03*
G54D26*
X45300Y1737100D03*
X97200Y513400D03*
G54D31*
X1019291Y1416024D03*
Y1694212D03*
G54D28*
X78749Y664550D03*
G54D33*
X85629Y141128D03*
Y146128D03*
Y156128D03*
Y161128D03*
X150590Y208924D03*
X878936D03*
X150590Y213924D03*
X878936D03*
X150590Y223924D03*
X878936D03*
X150590Y228924D03*
X878936D03*
X85629Y546640D03*
Y551640D03*
Y561640D03*
Y566640D03*
X150590Y614436D03*
X878936D03*
X150590Y619436D03*
X878936D03*
X150590Y629436D03*
X878936D03*
X150590Y634436D03*
X878936D03*
X85629Y952152D03*
Y957152D03*
Y967152D03*
Y972152D03*
X150590Y1019948D03*
X878936D03*
X150590Y1024948D03*
X878936D03*
X150590Y1034948D03*
X878936D03*
X150590Y1039948D03*
X878936D03*
X85629Y1357664D03*
Y1362664D03*
Y1372664D03*
Y1377664D03*
X150590Y1425460D03*
X878936D03*
X150590Y1430460D03*
X878936D03*
X150590Y1440460D03*
X878936D03*
X150590Y1445460D03*
X878936D03*
X85629Y1763176D03*
Y1768176D03*
Y1778176D03*
Y1783176D03*
X150590Y1830972D03*
X878936D03*
X150590Y1835972D03*
X878936D03*
X150590Y1845972D03*
X878936D03*
X150590Y1850972D03*
X878936D03*
G54D27*
X32299Y1497550D03*
G54D35*
X860838Y1872869D03*
X130116Y1872510D03*
X860838Y1848369D03*
X130116Y1848010D03*
X105522Y1765806D03*
X858820Y1467538D03*
X129414Y1442997D03*
X858820Y1442538D03*
X105852Y1360208D03*
X102352Y1335208D03*
X130973Y1079356D03*
X857320Y1062638D03*
X131022Y1061806D03*
X857320Y1037638D03*
X131022Y1037306D03*
X104568Y954745D03*
X101568Y929745D03*
X857720Y656638D03*
X133462Y656321D03*
X857720Y632138D03*
X133462Y631821D03*
X102468Y549244D03*
X102968Y524244D03*
X130022Y250806D03*
X857501Y226680D03*
X130022Y226306D03*
X102522Y143306D03*
X107022Y127806D03*
G54D19*
X129920Y17716D03*
X994093Y1889751D03*
G54D15*
X8750Y1086250D03*
X8499Y1937550D03*
X5303Y1947050D03*
X11703Y1951946D03*
X74499Y84050D03*
Y80650D03*
X86899Y130567D03*
X86599Y126750D03*
X74999Y74050D03*
Y70550D03*
X78700Y70700D03*
Y74200D03*
X15750Y102250D03*
X65999Y216050D03*
X95350Y204550D03*
X89800Y208550D03*
X26299Y383854D03*
Y387629D03*
X28100Y374000D03*
X26492Y439350D03*
X26599Y442749D03*
X26299Y399601D03*
Y403376D03*
Y478404D03*
X26899Y454850D03*
X26515Y481798D03*
X45800Y405200D03*
X26799Y458497D03*
X26486Y462648D03*
X26499Y466250D03*
X64403Y471046D03*
X64397Y474446D03*
X26524Y426720D03*
X26399Y423322D03*
X61400Y452600D03*
X35900Y412600D03*
X65000Y455500D03*
X28900Y417800D03*
X39217Y554750D03*
X42867Y548450D03*
X43099Y555850D03*
X33699Y561850D03*
X46299Y552950D03*
X36499Y517775D03*
Y521550D03*
X26399Y501966D03*
Y505741D03*
X64600Y486300D03*
X64700Y489700D03*
X33307Y557938D03*
X26199Y547176D03*
X29999Y557150D03*
X26599Y525648D03*
X95500Y513400D03*
X26599Y529302D03*
X60003Y534150D03*
X86199Y536025D03*
X59999Y537550D03*
X86199Y532250D03*
X65599Y514250D03*
X49799Y559150D03*
X68000Y546500D03*
X72500Y545000D03*
X27199Y539600D03*
X42202Y608195D03*
X39600Y626984D03*
X41400Y611500D03*
X42709Y625607D03*
X38300Y633800D03*
X41500Y642800D03*
X27499Y620203D03*
Y623857D03*
X36499Y566350D03*
X37999Y611550D03*
X42599Y567850D03*
X26568Y635950D03*
Y639604D03*
X47101Y632355D03*
X28000Y578500D03*
X25581Y567763D03*
X47626Y611300D03*
X45701Y607700D03*
X27699Y573750D03*
X82499Y627050D03*
X26800Y611500D03*
X41500Y635000D03*
X52500D03*
X48999Y642900D03*
X81251Y607249D03*
Y619251D03*
X28808Y593150D03*
X28700Y596549D03*
X32200Y603710D03*
X31598Y607102D03*
X80499Y664550D03*
X26737Y651957D03*
X26999Y656550D03*
X27687Y667447D03*
Y671101D03*
X76999Y664550D03*
X27700Y682700D03*
X50410Y695801D03*
X50300Y699200D03*
X44046Y799554D03*
X32800Y803050D03*
X46887Y803413D03*
X37416Y799033D03*
X37099Y811350D03*
X51100Y806300D03*
X49900Y813200D03*
X56281Y801350D03*
X27299Y783550D03*
X35300Y789375D03*
X35559Y795112D03*
X45100Y793100D03*
X37216Y807951D03*
X76540Y850938D03*
X29299Y836901D03*
X75500Y847700D03*
X49300Y836500D03*
X46700Y820100D03*
X40400Y840792D03*
X89000Y816500D03*
X48346Y844529D03*
X58699Y837250D03*
X68860Y838706D03*
X90000Y826000D03*
X54074Y815750D03*
X69499Y842950D03*
X62405Y820300D03*
X63499Y843050D03*
X90500Y831500D03*
X31699Y814350D03*
X65500Y817700D03*
X23299Y863050D03*
X26662Y861550D03*
X39649Y822000D03*
X80500Y817000D03*
X74220Y854150D03*
X72362Y849550D03*
X25000Y858100D03*
X46576Y832951D03*
X29600Y854000D03*
X24000Y853500D03*
X94999Y901550D03*
X85999Y940429D03*
X86399Y937050D03*
X29000Y896500D03*
X72000Y1013400D03*
X63273Y1023974D03*
X90000Y993100D03*
X92600Y996100D03*
X80699Y1004450D03*
Y1000450D03*
X66499Y1025050D03*
X75900Y1019100D03*
X63500Y1029600D03*
X88000Y1008500D03*
X75500Y1012261D03*
X76999Y1196550D03*
X21817Y1156317D03*
X25507Y1372045D03*
X25558Y1368447D03*
X86890Y1346635D03*
Y1342860D03*
X28499Y1391050D03*
X32333Y1389383D03*
X20999Y1352050D03*
Y1320550D03*
X77758Y1357742D03*
X25000D03*
X30378Y1462518D03*
X33915Y1462681D03*
X32094Y1448448D03*
X28697Y1448296D03*
X32451Y1411468D03*
X28999Y1411550D03*
X33206Y1432352D03*
X30499Y1434550D03*
X30500Y1395500D03*
X76000Y1431100D03*
X34896Y1555730D03*
X34099Y1497550D03*
X30499D03*
X80043Y1544691D03*
X83932Y1544705D03*
X29631Y1533063D03*
X31999Y1517846D03*
Y1521500D03*
X46700Y1546793D03*
X34465Y1481683D03*
X30999Y1482050D03*
X44299Y1550950D03*
X96200Y1550100D03*
X37999Y1530900D03*
X38500Y1534600D03*
X32099Y1535550D03*
X30115Y1511900D03*
X33512Y1512051D03*
X90324Y1538800D03*
X26705Y1534795D03*
X30199Y1545450D03*
X24199Y1523700D03*
X79000Y1555500D03*
X82429D03*
X36340Y1558809D03*
X78600Y1561900D03*
X29499Y1630050D03*
X75000Y1561800D03*
X28899Y1613524D03*
X42199Y1601050D03*
X38208Y1569841D03*
X25521Y1563350D03*
X30520Y1572049D03*
X32299Y1613524D03*
X34599Y1595300D03*
X32663Y1628181D03*
X27123Y1572205D03*
X33599Y1600200D03*
X74800Y1584700D03*
X74700Y1574600D03*
X39000Y1573500D03*
X89373Y1561073D03*
X85600Y1561500D03*
X80400Y1571766D03*
X82329Y1568117D03*
X31999Y1661127D03*
X28600Y1661039D03*
X29626Y1645002D03*
X33026Y1645051D03*
X95499Y1665418D03*
X93999Y1703050D03*
X74500Y1692000D03*
X21600Y1702900D03*
X32700Y1673300D03*
X32494Y1669706D03*
X29100Y1669500D03*
X30274Y1787238D03*
X85599Y1797350D03*
X38878Y1799571D03*
X47899Y1798650D03*
X36300Y1805123D03*
X35675Y1783450D03*
X39324Y1780623D03*
X39000Y1750800D03*
X43751Y1780559D03*
X42275Y1754000D03*
X48049Y1791450D03*
X85341Y1752245D03*
X85194Y1748848D03*
X46999Y1779550D03*
X37699Y1789850D03*
X46199Y1783050D03*
X74400Y1778100D03*
X38094Y1785840D03*
X41200Y1747050D03*
X42199Y1792250D03*
X37574Y1794050D03*
X45799Y1757650D03*
X46799Y1794900D03*
X47440Y1761391D03*
X31811Y1790271D03*
X47400Y1765250D03*
X43559Y1767884D03*
X40478Y1795820D03*
X32099Y1797150D03*
X47604Y1769005D03*
X45782Y1771877D03*
X47499Y1775350D03*
X45877Y1728477D03*
Y1724823D03*
X47000Y1737100D03*
X43600D03*
X28550Y1828153D03*
X29599Y1844350D03*
X29899Y1821050D03*
X34099Y1822850D03*
X80099Y1817250D03*
X28123Y1831527D03*
X35876Y1812350D03*
X34129Y1815267D03*
X86649Y1817100D03*
X61009Y1822340D03*
X36532Y1825352D03*
X36399Y1828750D03*
X26099Y1824950D03*
X25999Y1842550D03*
X46499Y1836550D03*
X47166Y1839884D03*
X80999Y1836550D03*
X90000Y1827900D03*
X43099Y1833850D03*
X39699D03*
X93500Y1827900D03*
X40500Y1863000D03*
X22367Y1836633D03*
X15099Y1944050D03*
X50499Y1961550D03*
X14999Y1936050D03*
X17499Y1961050D03*
X43462Y1961160D03*
X32999Y1960555D03*
X23030Y1922038D03*
X25499Y1956050D03*
X42499Y1902550D03*
X48499Y1897050D03*
X26765Y1921945D03*
X57999Y1891050D03*
X31799Y1979050D03*
X97499Y90050D03*
X115876Y125973D03*
Y130050D03*
X174999Y79050D03*
X175499Y86572D03*
X178999Y79050D03*
X176399Y94872D03*
X173500Y166315D03*
X154200Y168500D03*
X149400Y166400D03*
X149999Y243504D03*
Y239729D03*
X122397Y252688D03*
X122799Y249150D03*
X141499Y427550D03*
X165500Y416500D03*
X141499Y423050D03*
X159600Y446399D03*
X152000Y520813D03*
X171722Y513827D03*
X163549Y517100D03*
X140940Y561800D03*
X150500Y545000D03*
X135499Y517550D03*
X107499Y497050D03*
X98900Y513400D03*
X172499Y491053D03*
X137899Y545451D03*
X176799Y493850D03*
X150750Y540416D03*
X109400Y543200D03*
X149000Y537500D03*
X106000Y543200D03*
X156500Y554000D03*
X138416Y553500D03*
X125499Y635550D03*
Y638950D03*
X127999Y645550D03*
X131400Y644600D03*
X144238Y645356D03*
X107000Y604800D03*
X105100Y600000D03*
X157000Y573851D03*
X141300Y565900D03*
X160824Y577000D03*
X144238Y649131D03*
X111200Y799450D03*
X110195Y809979D03*
X110500Y790200D03*
X110700Y795700D03*
X109831Y806598D03*
X109700Y803200D03*
X110202Y813379D03*
X154799Y838050D03*
X165499Y815550D03*
X110499Y834550D03*
X169106Y815865D03*
X153900Y832200D03*
X98700Y842600D03*
Y822550D03*
X98000Y833500D03*
X163500Y937100D03*
X172500Y919294D03*
X108200Y963600D03*
X172000Y931600D03*
X153499Y918550D03*
X108845Y931657D03*
X109099Y928250D03*
X171100Y935000D03*
X102100Y968500D03*
X99000Y965000D03*
X172000Y961000D03*
X152500Y960000D03*
X170250Y948500D03*
X154749Y968249D03*
X171000Y939500D03*
X123999Y1054050D03*
Y1050650D03*
X112699Y1058974D03*
X104600Y980500D03*
X154749Y979149D03*
X103200Y985364D03*
X104700Y989900D03*
X120749Y1093990D03*
X164700Y1085400D03*
X105499Y1080550D03*
X106718Y1076050D03*
X105999Y1085800D03*
X101499Y1072550D03*
X125900Y1091282D03*
X132499Y1094550D03*
X123999Y1102550D03*
X138600Y1124600D03*
X116700Y1063500D03*
X105600Y1069500D03*
X108999Y1102050D03*
X137481Y1077557D03*
X137477Y1081177D03*
X124423Y1077523D03*
Y1081177D03*
X106999Y1194550D03*
X102900Y1196050D03*
X103686Y1223863D03*
X103999Y1216863D03*
X127000Y1202000D03*
X148000Y1206000D03*
X106162Y1205702D03*
X123970Y1221573D03*
X119399Y1298113D03*
X101541Y1262607D03*
X116999Y1288050D03*
X101399Y1292550D03*
X107999Y1307713D03*
X120507Y1317050D03*
X116499Y1328013D03*
X120507Y1328096D03*
X135850Y1322250D03*
X143700Y1332500D03*
X112440Y1358196D03*
X112999Y1361550D03*
X97229Y1373337D03*
X97000Y1377600D03*
X109228Y1337090D03*
Y1333315D03*
X102700Y1321363D03*
X119499Y1339050D03*
X121000Y1364000D03*
X148024Y1333525D03*
X140000Y1332600D03*
X129000Y1356500D03*
X113500Y1344500D03*
Y1348154D03*
X102350Y1344500D03*
Y1348154D03*
X147400Y1321600D03*
X125100Y1366000D03*
X124290Y1469241D03*
X123808Y1465050D03*
X117390Y1426201D03*
Y1429976D03*
X104935Y1440634D03*
X142999Y1456373D03*
X104999Y1444941D03*
X106999Y1454450D03*
X100699Y1471050D03*
X142900Y1460000D03*
X100800Y1536450D03*
X98599Y1491350D03*
X99899Y1539850D03*
X100000Y1546650D03*
X97499Y1554550D03*
X96999Y1558050D03*
X98144Y1534309D03*
X157400Y1596550D03*
X160200Y1598500D03*
X150999Y1713550D03*
X171999Y1662250D03*
X131999Y1710050D03*
X117499Y1706050D03*
X128749Y1703300D03*
X169100Y1685800D03*
X133090Y1699959D03*
X174250Y1694500D03*
X109499Y1712213D03*
X112753Y1716613D03*
X152633Y1677967D03*
X122642Y1704243D03*
X112562Y1720613D03*
X135499Y1710150D03*
X118499Y1694050D03*
X123749Y1711550D03*
X177900Y1690400D03*
X169600Y1682300D03*
X109499Y1743550D03*
X109399Y1739550D03*
X99199Y1761899D03*
X99999Y1753575D03*
X141999Y1764550D03*
X110099Y1759875D03*
X101399Y1784700D03*
X165900Y1790500D03*
X161900Y1793400D03*
X123393Y1870859D03*
X137999Y1861497D03*
Y1865151D03*
X123592Y1874254D03*
X96600Y1826000D03*
X97999Y1843050D03*
X186999Y99050D03*
X213499Y104650D03*
X223499Y108150D03*
X188999Y120800D03*
X205499Y105550D03*
X225499Y68550D03*
X233749Y110800D03*
X230749Y76300D03*
X207999Y109550D03*
X237899Y107050D03*
X218499Y190550D03*
X247800Y269700D03*
X225298Y281114D03*
X253871Y291410D03*
X250300Y275100D03*
X250400Y283100D03*
X239600Y278600D03*
X187699Y492850D03*
X199900Y554050D03*
X220000Y516400D03*
X183499Y556100D03*
X188000Y484500D03*
X246800Y677100D03*
X254499Y697700D03*
X249700Y682500D03*
X249800Y689900D03*
X238500Y680800D03*
X211750Y894600D03*
X200799Y896600D03*
X233500Y1066100D03*
X226800Y1093400D03*
X221800Y1069300D03*
X247500Y1085500D03*
X251500Y1136700D03*
X229800Y1073600D03*
X242000Y1066000D03*
X182500Y1275500D03*
X199149Y1362900D03*
X194700Y1385700D03*
X181000Y1365500D03*
X180500Y1369900D03*
X229025Y1471576D03*
X241000Y1469600D03*
X224750Y1483950D03*
X233700Y1481600D03*
X199500Y1627000D03*
X195000Y1645500D03*
X179999Y1644500D03*
X181100Y1682700D03*
X201499Y1781050D03*
X227814Y1887513D03*
X231800Y1887100D03*
X229800Y1875700D03*
X218100Y1886400D03*
X213138Y1952703D03*
X249499Y1928050D03*
X231999Y1914050D03*
X210999Y1942050D03*
X223436Y1890465D03*
X214999Y1909550D03*
X257499Y1911050D03*
X249600Y1896800D03*
X341499Y63050D03*
Y67110D03*
X343499Y31650D03*
X308999Y87050D03*
X323400Y105200D03*
X282800Y87500D03*
X297499Y97550D03*
X315800Y100500D03*
X324800Y89400D03*
X293999Y293550D03*
X326499Y334054D03*
X284999Y338650D03*
X281499Y338550D03*
X326499Y337454D03*
X301249Y346050D03*
X344520Y406329D03*
X279939Y728610D03*
X329499Y801550D03*
X330540Y795509D03*
X327999Y740550D03*
X320499Y798050D03*
X285499Y745050D03*
X282099D03*
X327749Y744050D03*
X306500Y753550D03*
X340699Y1046086D03*
X269500Y1135500D03*
X282500Y1135000D03*
X283499Y1556050D03*
X279999D03*
X326500Y1550200D03*
X261999Y1516050D03*
X295000Y1513000D03*
X333000Y1578000D03*
X330300Y1561200D03*
X310249Y1569800D03*
X264499Y1964050D03*
X331622Y1944767D03*
X288709Y1948042D03*
X284999Y1947691D03*
X342999Y1947409D03*
X342621Y1943409D03*
X330500Y1966500D03*
X332103Y1948133D03*
X310499Y1957050D03*
X285499Y1930050D03*
X381999Y57050D03*
Y53550D03*
X394199Y45050D03*
X358999Y61550D03*
X354999Y72050D03*
X371700Y85500D03*
X400499Y406329D03*
X371999Y549300D03*
X394649Y630600D03*
X350499Y597300D03*
X375999Y698550D03*
X350499Y715050D03*
X371500Y880600D03*
X364499Y1099050D03*
X372999Y1123550D03*
X345499Y1096550D03*
X370149Y1320050D03*
X345424Y1310050D03*
X347324Y1524000D03*
X366149Y1554050D03*
X402499Y1476850D03*
X390999Y1514398D03*
Y1517798D03*
X349774Y1582900D03*
X354500Y1559500D03*
X400999Y1575550D03*
X354000Y1584900D03*
X353499Y1710450D03*
X377900Y1703800D03*
X348499Y1762050D03*
X385499Y1735050D03*
X645549Y1815134D03*
X644360Y1819137D03*
X757499Y1079550D03*
X757999Y1484050D03*
X750000Y1560500D03*
X732549Y1806634D03*
X733149Y1798634D03*
X707600Y1815600D03*
X733049Y1814134D03*
X711652Y1822109D03*
X711848Y1825504D03*
X758499Y1893550D03*
X829917Y216200D03*
X833576Y215432D03*
X837999Y219550D03*
X822100Y279500D03*
X827500Y274500D03*
X809940Y264940D03*
X822100Y261700D03*
X816700Y274300D03*
X791499Y333050D03*
X789999Y336550D03*
X772499Y323050D03*
X772873Y326924D03*
X780499Y330050D03*
X771105Y722789D03*
X829800Y666650D03*
X781999Y725550D03*
X808660Y667540D03*
X820600Y664300D03*
X813200Y675900D03*
X788999Y736050D03*
X791999Y733050D03*
X769999D03*
X792154Y1135926D03*
X825700Y1083100D03*
X771999Y1124550D03*
X772499Y1130050D03*
X789499Y1138050D03*
X779499Y1131050D03*
X807000Y1072900D03*
X825800Y1072300D03*
X815400Y1078800D03*
X803199Y1151850D03*
X822100Y1466800D03*
X774542Y1530050D03*
X804899Y1556950D03*
X827700Y1487600D03*
X774577Y1533796D03*
X791499Y1543550D03*
X793999Y1541050D03*
X784499Y1529050D03*
X809960Y1478040D03*
X814700Y1486300D03*
X793000Y1803500D03*
X795849Y1805500D03*
X828500Y1877800D03*
X807000Y1822300D03*
X803500Y1822708D03*
X810900Y1882440D03*
X822700Y1871100D03*
X805900Y1887560D03*
X771499Y1936550D03*
X802499Y1951550D03*
X800431Y1941193D03*
X771499Y1940050D03*
X802099Y1961950D03*
X834799Y1946950D03*
X792499Y1949050D03*
X794499Y1941050D03*
X782999Y1937050D03*
X907499Y131800D03*
X902499Y110550D03*
X901499Y92050D03*
X898999Y110550D03*
X897555Y90494D03*
X910999Y124550D03*
X916499Y172550D03*
X867500Y163924D03*
X867576Y159924D03*
X878078Y240103D03*
Y243878D03*
X854400Y264600D03*
X847878Y250040D03*
X851278Y249974D03*
X842499Y280924D03*
X868799Y294750D03*
X865499Y288050D03*
X867899Y321550D03*
X868299Y336150D03*
X902999Y556050D03*
X878596Y645573D03*
X879750Y570550D03*
X879950Y565050D03*
X851172Y655432D03*
X878596Y649348D03*
X847772Y655370D03*
X852696Y671197D03*
X900499Y962100D03*
X879708Y971892D03*
X878233Y1051095D03*
X877964Y1054485D03*
X850833Y1061441D03*
X847233Y1061492D03*
X900999Y979050D03*
X883083Y979183D03*
X864499Y1128750D03*
X852333Y1077716D03*
X861849Y1376050D03*
X866700Y1379796D03*
X866596Y1375796D03*
X848888Y1466402D03*
X852288Y1466346D03*
X878054Y1456450D03*
X877853Y1459991D03*
X867523Y1542821D03*
X867199Y1535150D03*
X854327Y1477550D03*
X863699Y1501250D03*
X886439Y1717600D03*
X862800Y1712700D03*
X889800Y1711500D03*
X917499Y1796550D03*
X879700Y1786300D03*
X873300Y1740100D03*
X879664Y1782213D03*
X866914Y1861840D03*
X853499Y1871036D03*
X866914Y1865615D03*
X850099Y1871056D03*
X854814Y1883550D03*
X863699Y1906450D03*
X857099Y1917650D03*
X930999Y115550D03*
X937999Y122050D03*
X938499Y115550D03*
X961499Y93350D03*
X926999Y122050D03*
X943499Y82550D03*
X934499Y118750D03*
X926999Y115050D03*
X986400Y1639302D03*
X987100Y1624900D03*
X981200Y1625800D03*
X964000Y1639200D03*
X960900Y1636400D03*
X969600Y1638300D03*
X977500Y1660500D03*
X978000Y1668000D03*
X967600Y1651100D03*
X974000Y1670700D03*
X984211Y1667500D03*
X971558Y1646500D03*
X981500Y1653000D03*
X980800Y1659600D03*
X982050Y1649302D03*
G54D20*
X167323Y179803D03*
Y353031D03*
Y585315D03*
Y758543D03*
Y990827D03*
Y1164055D03*
Y1396339D03*
Y1569567D03*
Y1801851D03*
Y1975079D03*
X895669Y179803D03*
Y353031D03*
Y585315D03*
Y758543D03*
Y990827D03*
Y1164055D03*
Y1396339D03*
Y1569567D03*
Y1801851D03*
Y1975079D03*
G54D14*
X6500Y1098000D03*
Y1103500D03*
Y1110000D03*
Y1116500D03*
X92999Y52050D03*
X88000Y36400D03*
X93000Y44900D03*
X92900Y39700D03*
X32400Y115400D03*
X37000Y115300D03*
X32300Y121000D03*
X36900Y120900D03*
X32100Y130700D03*
X37000D03*
X32100Y136600D03*
X36800Y136700D03*
X36500Y179000D03*
Y188500D03*
X35000Y198500D03*
X30000Y179000D03*
X23500D03*
X30000Y188500D03*
X24000D03*
X29000Y198000D03*
X23500D03*
X94500Y456800D03*
X93499Y481550D03*
Y477050D03*
X93199Y449850D03*
X93500Y445300D03*
X94499Y486550D03*
X44000Y728500D03*
X40000Y729000D03*
X43499Y657550D03*
X44500Y733000D03*
X40000D03*
X43999Y737550D03*
X39999Y738050D03*
X44499Y742050D03*
X39999D03*
X93299Y862050D03*
X93690Y887139D03*
X93900Y882400D03*
X94001Y856895D03*
X93808Y852063D03*
X93499Y892050D03*
X67000Y1011500D03*
X22500Y1183000D03*
Y1176500D03*
Y1170000D03*
Y1164500D03*
X83499Y1602050D03*
X92499Y1589050D03*
X86999D03*
X83499Y1594050D03*
Y1598050D03*
X74999Y1602050D03*
X78999D03*
X81499Y1589050D03*
X78999Y1593550D03*
X74999Y1598050D03*
Y1593550D03*
X78999Y1598050D03*
X82999Y1887550D03*
X78999D03*
X58999Y1958050D03*
X82499Y1957050D03*
X73499D03*
X66499D03*
X92499Y1959050D03*
X47499Y1915050D03*
X62999Y1914550D03*
Y1926050D03*
X81499Y1915550D03*
X47499Y1930550D03*
X62499Y1939550D03*
X73499Y1945550D03*
X83999Y1945050D03*
X78999Y1891550D03*
X82999D03*
X78999Y1896050D03*
X78433Y1900010D03*
X78999Y1904050D03*
X83499Y1896050D03*
X83433Y1904010D03*
X83999Y1900050D03*
X96999Y49550D03*
X97800Y36000D03*
X96900Y40400D03*
X167499Y43550D03*
X116400Y56000D03*
X129100Y55900D03*
X127499Y65050D03*
X141999Y65550D03*
X156499Y66050D03*
X129999Y78050D03*
X166999Y88050D03*
X166499Y83550D03*
Y79050D03*
X158499D03*
Y84050D03*
Y88550D03*
Y93550D03*
X166999Y92550D03*
Y97050D03*
X127999Y99550D03*
X165499Y106050D03*
X169999Y103050D03*
X114800Y68500D03*
X97999Y199050D03*
X155999Y181050D03*
X137100Y436800D03*
X129400Y426900D03*
X135999Y472550D03*
X135140Y478930D03*
X100500Y456700D03*
X97699Y477050D03*
Y481550D03*
X149700Y471600D03*
X154100Y476500D03*
X164600Y476700D03*
X171300D03*
X97999Y445550D03*
X97699Y449850D03*
X147300Y526700D03*
X147590Y521500D03*
X145649Y509550D03*
X136349Y509050D03*
X98999Y488050D03*
X140499Y499050D03*
X153499Y502550D03*
X148999D03*
X136299Y499050D03*
X152499Y810550D03*
X161999Y768050D03*
X152499Y816050D03*
Y820550D03*
Y825050D03*
X156499Y876050D03*
Y870550D03*
X97499Y862050D03*
X155499Y891050D03*
Y896050D03*
X97700Y887400D03*
X97900Y882400D03*
X163999Y863050D03*
X159999D03*
X155999Y859050D03*
Y863050D03*
X97800Y851800D03*
X98001Y856950D03*
X97499Y892550D03*
X151999Y936550D03*
X152499Y931550D03*
X159459Y896616D03*
X163499Y896550D03*
X157499Y909050D03*
Y904550D03*
X159186Y946117D03*
X151300Y1049300D03*
X100999Y1099550D03*
X105000Y1100500D03*
X100999Y1095050D03*
X105006Y1095366D03*
X110999Y1130550D03*
X115200Y1130300D03*
X110999Y1126050D03*
Y1122050D03*
Y1118050D03*
X114999Y1126050D03*
Y1122050D03*
Y1118050D03*
X144149Y1226113D03*
Y1222113D03*
X148499D03*
Y1226113D03*
X144149Y1230113D03*
X148486D03*
X175823Y1297070D03*
X175499Y1302113D03*
Y1306113D03*
Y1292550D03*
X123500Y1360300D03*
X105749Y1712749D03*
X172499Y1714050D03*
X167499Y1714113D03*
X162499D03*
X130499Y1730050D03*
X128000Y1735000D03*
X144499Y1729550D03*
X139500Y1730500D03*
X133000Y1734500D03*
X170499Y1731050D03*
X165499Y1730613D03*
X172499Y1726613D03*
X167999D03*
X163499D03*
X132700Y1972400D03*
X137900Y1972200D03*
X126500Y1972400D03*
X131100Y1908500D03*
X129600Y1912400D03*
X124433Y1908510D03*
X124999Y1912550D03*
X98433Y1940510D03*
X98999Y1944550D03*
X102433Y1940555D03*
X103433Y1944510D03*
X132700Y1978600D03*
X137900Y1978400D03*
X126600Y1978500D03*
X119999Y1978550D03*
X119499Y1972550D03*
X189499Y39150D03*
X197999Y39900D03*
X193999D03*
X208499Y45650D03*
X199999Y46050D03*
X194499Y44050D03*
X225499Y52550D03*
Y46550D03*
Y63550D03*
Y58050D03*
X183499Y45550D03*
X192499Y57550D03*
X227499Y192050D03*
X231999D03*
X227999Y187050D03*
X231999D03*
X227999Y182550D03*
X231999D03*
X227999Y178050D03*
X231999D03*
X179999Y442550D03*
X179649Y438550D03*
X183999D03*
Y442550D03*
Y447050D03*
X179999D03*
X194999Y490050D03*
X190499Y487550D03*
X191199Y491550D03*
X187499Y531613D03*
Y536113D03*
X193499Y541113D03*
X188999D03*
X193499Y549613D03*
X188999D03*
Y545613D03*
X193999Y545550D03*
X215999Y887550D03*
X220499D03*
X215499Y883550D03*
X204496Y846111D03*
X204649Y838050D03*
X208999D03*
X209000Y846113D03*
X204649Y842113D03*
X208986D03*
X219499Y939613D03*
Y948613D03*
Y943813D03*
X214999Y939613D03*
Y944113D03*
Y948613D03*
X219499Y926613D03*
X214999D03*
X259999Y1152992D03*
X259499Y1161550D03*
X179999Y1306050D03*
Y1301550D03*
Y1292550D03*
Y1296613D03*
X260999Y1503550D03*
X180299Y1626550D03*
X180000Y1619600D03*
X195700Y1619100D03*
X195600Y1623700D03*
X180299Y1634550D03*
X179733Y1630590D03*
X226999Y1941050D03*
X289499Y39050D03*
X286603Y34928D03*
X290999Y67550D03*
X300700Y39400D03*
X304500Y44500D03*
X305100Y39700D03*
X294100Y28000D03*
X308900Y41000D03*
X308800Y46400D03*
X289999Y72550D03*
X288499Y76550D03*
X289499Y80550D03*
X308499Y72550D03*
X303999Y74050D03*
X307999Y78550D03*
X279998Y308614D03*
Y304114D03*
Y299614D03*
Y295114D03*
X267498Y310114D03*
Y305114D03*
Y300114D03*
Y295114D03*
X305998Y352114D03*
X293998Y361114D03*
Y356614D03*
Y352114D03*
X289998Y361114D03*
Y356614D03*
Y352114D03*
X268499Y716550D03*
Y711550D03*
Y701550D03*
Y706550D03*
X280999Y717550D03*
X280433Y713590D03*
X280999Y701550D03*
Y705550D03*
X294999Y767050D03*
X290999D03*
X294999Y762550D03*
Y758050D03*
X290999Y762550D03*
Y758050D03*
X306999D03*
X272499Y1153050D03*
X268499D03*
X263999D03*
X271999Y1161550D03*
X267999D03*
X263499D03*
X267349Y1518150D03*
Y1522550D03*
X266999Y1512550D03*
X267349Y1527172D03*
X279499Y1510550D03*
Y1515050D03*
X279075Y1525957D03*
X278567Y1529925D03*
X305998Y1569114D03*
X293998Y1578114D03*
Y1573614D03*
Y1569114D03*
X289998Y1578114D03*
Y1573614D03*
Y1569114D03*
X334999Y1797050D03*
X326301Y1766030D03*
X306999Y1932550D03*
X302499D03*
X298499D03*
X293999Y1933050D03*
X306000Y1961500D03*
X305500Y1965500D03*
X293999Y1971050D03*
Y1966550D03*
Y1962050D03*
X289499Y1961550D03*
Y1966550D03*
Y1971050D03*
X281999Y1918550D03*
Y1923550D03*
Y1928550D03*
X266999Y1915550D03*
Y1920050D03*
Y1924550D03*
Y1929050D03*
Y1933550D03*
X381499Y65550D03*
X376999D03*
X371999Y15550D03*
X376499D03*
X380999D03*
X369999Y23550D03*
Y19050D03*
X382499Y20050D03*
X381499Y70050D03*
X376999D03*
X360999Y113050D03*
X356499D03*
X351999D03*
X347499D03*
X360999Y100550D03*
X355999D03*
X350999D03*
X345999D03*
X558099Y335050D03*
X557933Y331010D03*
X557999Y322550D03*
Y326550D03*
X558499Y616050D03*
X554304Y615840D03*
X554499Y624550D03*
X558699D03*
X554499Y620050D03*
X558709Y620245D03*
X563499Y1497550D03*
Y1486550D03*
Y1503550D03*
Y1492050D03*
X544300Y1784638D03*
X633837Y1807384D03*
X757999Y154550D03*
Y159050D03*
X753999Y154550D03*
Y159050D03*
X755499Y314550D03*
X751539Y313984D03*
X755346Y319149D03*
X751499Y318050D03*
X748000Y357500D03*
X751499Y679148D03*
X749499Y716050D03*
X744999Y715550D03*
X749999Y720050D03*
X745499D03*
X750000Y755500D03*
X755499Y1119050D03*
X749999Y1119550D03*
X748999Y1115550D03*
X748499Y1111550D03*
X747000Y1159000D03*
X751000Y1517000D03*
X757500Y1522500D03*
X751000Y1521000D03*
Y1525000D03*
X751999Y1775550D03*
X756617Y1780067D03*
X752657Y1779496D03*
X755999Y1775550D03*
X756900Y1766000D03*
X753558Y1769946D03*
X757518Y1770517D03*
X752900Y1766000D03*
X717000Y1812384D03*
X750000Y1965500D03*
X840499Y55050D03*
X839999Y46050D03*
X840999Y62550D03*
X837999Y91050D03*
X838999Y85050D03*
X838499Y99550D03*
Y107050D03*
X839499Y119050D03*
X841499Y71550D03*
X809373Y307571D03*
Y297571D03*
Y292571D03*
X808999Y303050D03*
X796873Y307571D03*
Y303071D03*
Y298571D03*
Y294071D03*
X784478Y355424D03*
Y359924D03*
X781478Y363924D03*
X776978D03*
X772478Y359924D03*
Y363924D03*
X806831Y701853D03*
Y706853D03*
Y711853D03*
X794331Y698353D03*
Y702853D03*
Y707353D03*
Y711853D03*
X806999Y697050D03*
X771196Y764382D03*
Y760382D03*
X775696Y764382D03*
X780196D03*
X783196Y760382D03*
Y755882D03*
X799385Y761436D03*
X811499Y1097050D03*
X807499D03*
X807341Y1116216D03*
Y1111216D03*
Y1101216D03*
X806999Y1106050D03*
X802499Y1097566D03*
X798499D03*
X783333Y1157392D03*
Y1161892D03*
X780333Y1165892D03*
X775833D03*
X771333Y1161892D03*
Y1165892D03*
X809245Y1518722D03*
Y1508722D03*
Y1503722D03*
X795999Y1518550D03*
Y1514050D03*
Y1509550D03*
Y1504550D03*
X808999Y1513550D03*
X785827Y1561296D03*
Y1565796D03*
X782827Y1569796D03*
X778327D03*
X773327Y1565796D03*
X773827Y1569796D03*
X767159Y1792364D03*
X773999Y1923550D03*
X767999Y1923050D03*
X774499Y1930050D03*
X768999D03*
X783814Y1967213D03*
Y1971713D03*
X795526Y1909696D03*
X795493Y1913696D03*
X795501Y1917696D03*
X795499Y1922050D03*
X807997Y1922865D03*
X808005Y1918865D03*
X807936Y1914865D03*
Y1910365D03*
X784016Y1975708D03*
X775814Y1975699D03*
X771814Y1975713D03*
X902999Y22050D03*
X917499Y21550D03*
X909499D03*
X902499Y35050D03*
X909999Y35550D03*
X916499Y36050D03*
X854499Y39550D03*
X865499D03*
X883999Y39050D03*
X904999Y61550D03*
Y67550D03*
X905499Y56550D03*
X843499Y82550D03*
X855499Y82050D03*
X876999D03*
X867499D03*
X845999Y111050D03*
X886499Y99550D03*
Y104550D03*
X890459Y100116D03*
X890499Y104550D03*
X865499Y125550D03*
X875499D03*
X856499Y71050D03*
X881499Y70550D03*
X866999D03*
X904499Y74050D03*
X903999Y574378D03*
X866499Y724550D03*
X873499Y1356050D03*
X882200Y1744800D03*
X886400Y1744400D03*
X904814Y1789113D03*
X864414Y1940050D03*
X945499Y33550D03*
X940499Y33050D03*
X929999Y32550D03*
X928499Y51550D03*
X943499Y48050D03*
Y55050D03*
X928999Y56050D03*
X928499Y60550D03*
X928999Y65550D03*
X942999Y61550D03*
Y66550D03*
X943499Y72550D03*
Y78050D03*
X973500Y1474000D03*
X971500Y1467500D03*
X971700Y1457800D03*
Y1462300D03*
X972000Y1442000D03*
Y1437500D03*
X971700Y1448300D03*
Y1452800D03*
X962500Y1436500D03*
Y1441000D03*
X952800Y1437500D03*
Y1442000D03*
X962000Y1466500D03*
X966000Y1475000D03*
X952300Y1467500D03*
X958800Y1472500D03*
X962200Y1447300D03*
Y1451800D03*
X952500Y1448300D03*
Y1452800D03*
X962200Y1456800D03*
Y1461300D03*
X952500Y1457800D03*
Y1462300D03*
X972549Y1502300D03*
Y1506800D03*
X973500Y1483000D03*
Y1478500D03*
X973200Y1488300D03*
X972700Y1497300D03*
X966000Y1479500D03*
Y1484000D03*
X958800Y1477000D03*
Y1481500D03*
X965700Y1489300D03*
X960200Y1495300D03*
X958500Y1486800D03*
X951500Y1495300D03*
X960049Y1500300D03*
X951349D03*
X960049Y1504800D03*
X951349D03*
X950100Y1626100D03*
G54D22*
X210638Y62959D03*
X210634Y66863D03*
X215138Y72559D03*
X210685Y74725D03*
X210605Y70692D03*
X205938Y72528D03*
X210738Y78459D03*
Y82159D03*
X232400Y220700D03*
X210999Y221550D03*
X191999D03*
X217999Y250550D03*
X203499D03*
X185999D03*
X251499Y446050D03*
X231999Y445550D03*
X251999Y462050D03*
X232499Y461550D03*
X209499Y412550D03*
X220000Y421000D03*
X232999Y414550D03*
X252499Y415050D03*
X343999Y190050D03*
X337999Y219050D03*
X310499Y216550D03*
X290999Y216050D03*
X271999D03*
X297999Y245050D03*
X283499D03*
X265999D03*
X343499Y253550D03*
X337499Y282550D03*
X327900Y463200D03*
X306100Y462000D03*
X286999Y462050D03*
X272499Y445050D03*
X272999Y461050D03*
X269999Y415050D03*
X284499D03*
X303999Y415550D03*
X324999Y414550D03*
X333499Y483050D03*
X312499Y484050D03*
X292999Y483550D03*
X369999Y219050D03*
X382499Y190550D03*
X355499Y219050D03*
X362999Y190050D03*
X369499Y282550D03*
X381999Y254050D03*
X354999Y282550D03*
X362499Y253550D03*
X415999Y518550D03*
X444499Y283050D03*
X463999Y283550D03*
X481499D03*
X495999D03*
X448999Y255550D03*
X469999Y254550D03*
X508499Y255050D03*
X488999Y254550D03*
X438999Y381550D03*
X458499Y382050D03*
X484900Y394700D03*
X485000Y373200D03*
X509999Y382550D03*
X443499Y354050D03*
X464499Y353050D03*
X502999Y353550D03*
X483499Y353050D03*
X456499Y518050D03*
X435499Y519050D03*
X515499Y284050D03*
X536499Y283050D03*
X525999Y255050D03*
X540499D03*
X530999Y381550D03*
X520499Y353550D03*
X548100Y362200D03*
X579499Y561550D03*
X558499Y562550D03*
X538999Y562050D03*
X535499Y545050D03*
X514499Y546050D03*
X674999Y601550D03*
X646999Y584550D03*
X625999Y585050D03*
X606499Y584550D03*
X744999Y626550D03*
X721499Y617550D03*
X699999Y610050D03*
X757400Y686300D03*
X785499Y641050D03*
X777499Y638050D03*
X771800Y686600D03*
X786500Y686100D03*
X798000Y686400D03*
X777499Y664550D03*
X794999D03*
X806300Y670600D03*
X841000Y671100D03*
X923761Y85550D03*
X932961Y85581D03*
X928461Y75981D03*
X928561Y91481D03*
X928508Y87747D03*
X928428Y83714D03*
X928561Y95181D03*
X928457Y79885D03*
G54D13*
X6891Y161611D03*
X7089Y166111D03*
X8599Y751650D03*
X10999Y774050D03*
X9399Y1347350D03*
X7099Y1717750D03*
X7199Y1731450D03*
X6099Y1753750D03*
X11299Y1850050D03*
X9099Y1881550D03*
X8499Y1979550D03*
X11500Y1987000D03*
X90899Y14850D03*
X23499Y27050D03*
X50999Y21150D03*
Y47750D03*
X27799Y38450D03*
X25799Y64050D03*
X65499Y59050D03*
Y41550D03*
Y27050D03*
X40999Y42050D03*
Y27550D03*
X17600Y5604D03*
X36000D03*
X55700Y5900D03*
X73900Y6200D03*
X90900Y5800D03*
X93999Y58550D03*
X92900Y66128D03*
X52499Y145050D03*
Y130550D03*
X59499Y108050D03*
Y90550D03*
Y76050D03*
X89800Y132400D03*
X96184Y151065D03*
X71015Y123666D03*
X78165Y137116D03*
X95814Y136065D03*
X77165Y110799D03*
X92999Y86128D03*
Y96128D03*
X15302Y161500D03*
X19500D03*
X15500Y166000D03*
X19198Y152000D03*
X19698Y166000D03*
X92899Y231450D03*
X48499Y228550D03*
X23999Y229050D03*
X52499Y162550D03*
X96184Y166065D03*
X41999Y200050D03*
X23895Y238995D03*
X24300Y247300D03*
X51099Y300050D03*
X90899Y309550D03*
X93199Y279650D03*
X84899Y289250D03*
X86899Y242750D03*
X75299Y261750D03*
X42999Y275650D03*
X48499Y260550D03*
Y243050D03*
X23999Y261050D03*
Y243550D03*
X52199Y342350D03*
X89899Y368350D03*
X94199Y325550D03*
X93499Y337450D03*
X95499Y355450D03*
X89999Y396450D03*
X39999Y359550D03*
Y342050D03*
Y327550D03*
X15499Y360050D03*
Y342550D03*
Y328050D03*
X29699Y388484D03*
X29599Y382884D03*
X29999Y398684D03*
X23499Y397579D03*
X23399Y373931D03*
Y389679D03*
X23499Y381831D03*
X75300Y454100D03*
X67300Y450200D03*
X68899Y445450D03*
X87599Y403950D03*
X76099Y414250D03*
X95399Y416350D03*
X89099Y426150D03*
X29899Y404384D03*
X28900Y429200D03*
X29365Y421169D03*
X29500Y460800D03*
X28700Y451900D03*
X28800Y436700D03*
X28700Y445700D03*
X68000Y475600D03*
X67800Y469900D03*
X23499Y468447D03*
X23399Y476295D03*
Y444799D03*
X23499Y452699D03*
X23399Y460547D03*
Y429051D03*
X23499Y436951D03*
X23600Y405700D03*
X77499Y469550D03*
X93200Y510500D03*
X83700Y529500D03*
X28600Y508500D03*
X42299Y564150D03*
X62055Y561550D03*
X49555Y563550D03*
X35300Y524800D03*
X38400Y514900D03*
X88999Y538050D03*
X68900Y490600D03*
X68700Y485200D03*
X28600Y499300D03*
X26900Y532800D03*
X63499Y538550D03*
Y533050D03*
X75999Y556640D03*
X70800Y540300D03*
X22800Y539600D03*
X77165Y514650D03*
X23499Y515691D03*
X23399Y523539D03*
X23499Y531439D03*
X23399Y492043D03*
X23499Y499943D03*
X23399Y507791D03*
X23499Y484195D03*
X77999Y493050D03*
X77499Y502550D03*
X32800Y578200D03*
X47543Y578340D03*
X44959Y575756D03*
X52333Y641295D03*
X72599Y578236D03*
X39999Y576550D03*
X61099Y603236D03*
X93599Y581236D03*
X92599Y606236D03*
X30712Y624971D03*
X29999Y640550D03*
X60076Y595777D03*
X55499Y595650D03*
X29819Y634951D03*
X26869Y616861D03*
X23399Y641649D03*
X23499Y618053D03*
X23799Y625950D03*
X23499Y633801D03*
X23999Y609250D03*
X93100Y571640D03*
X22978Y588571D03*
X22699Y577950D03*
X22999Y565550D03*
X57800Y634300D03*
X34976Y619250D03*
X44900Y642800D03*
X47800Y692800D03*
X53210Y701486D03*
X30999Y656250D03*
X29999Y694550D03*
X30999Y650550D03*
X81999Y668050D03*
X74499Y662050D03*
X25999Y694870D03*
X23999Y689050D03*
X23499Y665297D03*
X23699Y673150D03*
X23499Y681045D03*
Y649549D03*
X23725Y657471D03*
X78499Y654050D03*
X90700Y792900D03*
X39899Y754850D03*
X39399Y768750D03*
X27199Y764950D03*
X28599Y775450D03*
X26399Y750850D03*
X14799Y751450D03*
X17299Y773950D03*
X79900Y791300D03*
X67999Y790400D03*
X53999Y791000D03*
X26299Y815050D03*
X26799Y874550D03*
X26099Y891650D03*
X76399Y820450D03*
X70100Y818900D03*
X92999Y868550D03*
X92499Y876550D03*
X25699Y916150D03*
X25099Y942150D03*
X23899Y957950D03*
X89400Y935400D03*
X89499Y942850D03*
X93499Y897152D03*
X93000Y907165D03*
X77499Y921550D03*
X77002Y952079D03*
X76711Y948089D03*
X77499Y962152D03*
X83988Y934028D03*
X24799Y992250D03*
X33899Y1005950D03*
X65799Y994050D03*
X72799Y982950D03*
X86900Y981600D03*
X20400Y1048300D03*
X80000Y1090500D03*
X80500Y1097550D03*
Y1104500D03*
X22447Y1223247D03*
X23200Y1209300D03*
X78499Y1273550D03*
X78613Y1282664D03*
X78779Y1302664D03*
X22321Y1231121D03*
X18099Y1343550D03*
X91279Y1340642D03*
X89999Y1348050D03*
X27499Y1387550D03*
X96000Y1369000D03*
X96100Y1384650D03*
X24499Y1389663D03*
X22851Y1374169D03*
X22999Y1366050D03*
X77166Y1353400D03*
X93316Y1351000D03*
X23700Y1354600D03*
X77165Y1327335D03*
X23499Y1381500D03*
X78779Y1312664D03*
X86165Y1339050D03*
X33000Y1393000D03*
X33400Y1408100D03*
X36198Y1446749D03*
X26800Y1443800D03*
X30600Y1415100D03*
X30999Y1438050D03*
X27999Y1430050D03*
X29100Y1459200D03*
X34200Y1466200D03*
X23028Y1468579D03*
X23499Y1460550D03*
X22999Y1453050D03*
X23499Y1445050D03*
X22999Y1437050D03*
X23999Y1429050D03*
X23499Y1421550D03*
X23999Y1413550D03*
X76499Y1507050D03*
Y1498050D03*
Y1512050D03*
Y1503050D03*
X76999Y1528050D03*
Y1519050D03*
X32700Y1485200D03*
X28999Y1478050D03*
X27100Y1494300D03*
X34900Y1501000D03*
X35400Y1522200D03*
X35999Y1514550D03*
X29600Y1515300D03*
X24423Y1527123D03*
X22999Y1500050D03*
Y1515550D03*
X23799Y1508050D03*
X24499Y1492050D03*
X23599Y1476350D03*
X23277Y1484050D03*
X25247Y1546912D03*
X90999Y1628550D03*
Y1624550D03*
X91121Y1632549D03*
X86299Y1632550D03*
X85999Y1628550D03*
Y1624550D03*
X24900Y1569500D03*
X31149Y1568300D03*
X26999Y1610550D03*
X34884Y1615734D03*
X32199Y1633124D03*
X34816Y1630953D03*
X22999Y1626050D03*
X23499Y1634050D03*
Y1618050D03*
X22699Y1594224D03*
X23499Y1610050D03*
Y1602050D03*
X23608Y1572653D03*
X24323Y1559950D03*
X31099Y1595350D03*
X33100Y1648500D03*
X47400Y1721700D03*
X15299Y1723450D03*
X15399Y1708350D03*
X34699Y1663300D03*
X27499Y1657050D03*
X26785Y1642089D03*
X22999Y1665550D03*
X92873Y1708176D03*
X24244Y1681868D03*
X22864Y1673550D03*
X23499Y1657050D03*
X23999Y1649550D03*
X23415Y1641634D03*
X92479Y1718176D03*
X78100Y1688189D03*
X92900Y1678176D03*
X40400Y1735600D03*
X47900Y1731300D03*
X47800Y1740500D03*
X14899Y1736250D03*
X15299Y1753250D03*
X89306Y1746856D03*
X89499Y1753575D03*
X84099Y1737150D03*
X83599Y1744750D03*
X77165Y1759550D03*
X93499D03*
X94336Y1773113D03*
X78529Y1788113D03*
X38600Y1880200D03*
X31400Y1885200D03*
X30400Y1849650D03*
X23999Y1857950D03*
X27199Y1874350D03*
X52999Y1871550D03*
X60449Y1842550D03*
X57499Y1871050D03*
X36100Y1892200D03*
X50299Y1946650D03*
X53999D03*
X42532Y1946783D03*
X44399Y1942250D03*
X38703Y1946754D03*
X34799Y1946750D03*
X46565Y1946703D03*
X44368Y1951450D03*
X45999Y1971450D03*
X28799Y1919060D03*
X14999Y1940050D03*
X79500Y1987500D03*
X61500D03*
X44500Y1987000D03*
X26500D03*
X55999Y1982550D03*
X157299Y5150D03*
X107000Y6000D03*
X169300Y130300D03*
X178700Y129900D03*
X152999Y141050D03*
X123499Y149050D03*
X133999D03*
X142999Y141050D03*
X132999Y141550D03*
X176499Y140050D03*
X167499Y149550D03*
X144499Y149050D03*
X163499Y140050D03*
X160999Y149550D03*
X123499Y140050D03*
X112999Y124050D03*
X111790Y132259D03*
X152499Y149550D03*
X173499Y149050D03*
X175999Y82428D03*
X127999Y157050D03*
X177899Y199250D03*
X117500Y162300D03*
X124300Y167800D03*
X131799Y201950D03*
X142688Y218861D03*
X143110Y203861D03*
X114900Y177900D03*
X135399Y277050D03*
X130799Y300250D03*
X147099Y245350D03*
X124999Y246050D03*
X123300Y256000D03*
X158999Y259800D03*
X152808Y246341D03*
X166800Y240800D03*
X133000Y240500D03*
X157740Y273924D03*
X157440Y283924D03*
Y303924D03*
Y313924D03*
X139399Y372350D03*
X167299Y369350D03*
X130099Y326150D03*
X134699Y356050D03*
X126099Y396150D03*
X152499Y395950D03*
X99399Y437450D03*
X124899Y409050D03*
X133499Y445050D03*
X166500Y428500D03*
X153459Y427494D03*
X128999Y445550D03*
X130000Y452000D03*
X154101Y445550D03*
X102100Y514900D03*
X163449Y521650D03*
X108599Y557236D03*
X154099Y529236D03*
X107526Y528996D03*
X104502Y530552D03*
X138999Y524213D03*
X101500Y536500D03*
X173100Y483100D03*
X139200Y484300D03*
X134499Y488050D03*
X168453Y527949D03*
X160932Y549468D03*
X161000Y639100D03*
X108900Y587600D03*
X162500Y623400D03*
X140000Y587700D03*
X140499Y600550D03*
X124999Y643050D03*
X129000Y636600D03*
X128600Y640500D03*
X140900Y644000D03*
X134300Y646400D03*
X152400Y643300D03*
X140499Y626050D03*
X143999Y605550D03*
X170799Y689150D03*
X171999Y672450D03*
X131099Y700450D03*
X139099Y707150D03*
X140400Y649800D03*
X152124Y651868D03*
X159054Y665400D03*
X158885Y679436D03*
Y689436D03*
X141500Y711000D03*
X158385Y719436D03*
X110800Y772700D03*
X178899Y765250D03*
X172599Y774250D03*
X111299Y821050D03*
X172099Y877450D03*
X168499Y846713D03*
X173899Y846550D03*
X161999Y843550D03*
Y848050D03*
X156499Y846050D03*
X156999Y850050D03*
X158114Y883290D03*
X156499Y886950D03*
X172660Y815731D03*
X174199Y841050D03*
X159500Y814700D03*
X109500Y901100D03*
X153299Y943750D03*
X106500Y943000D03*
X105300Y960300D03*
X169299Y956350D03*
X106749Y934367D03*
X108441Y924705D03*
X160399Y922850D03*
X120100Y1053200D03*
X171499Y998650D03*
X156499Y985950D03*
X149499Y997650D03*
X162499Y1023550D03*
X163499Y1035050D03*
X124100Y1047100D03*
X158300Y1015000D03*
X141234Y1029885D03*
X140864Y1044885D03*
X159499Y1044579D03*
X165600Y1057428D03*
X137900Y1103400D03*
X139100Y1097100D03*
X137100Y1084800D03*
X140800Y1076300D03*
X121500Y1083600D03*
X121100Y1075300D03*
X169299Y1067150D03*
X168099Y1083550D03*
X167999Y1092850D03*
X143200Y1116300D03*
X134500Y1108100D03*
X171599Y1139950D03*
X167499Y1118550D03*
X167999Y1130550D03*
X133200Y1132100D03*
X164999Y1075550D03*
X159055Y1070400D03*
X116249Y1102550D03*
X112999Y1103740D03*
X117499Y1079300D03*
X157700Y1114948D03*
X157600Y1124948D03*
X159000Y1083000D03*
X106999Y1114960D03*
X127000Y1113500D03*
X145900Y1163200D03*
X163499Y1171650D03*
X151699Y1158550D03*
X144399Y1171150D03*
X150999Y1181150D03*
X141499Y1185550D03*
X151499Y1173050D03*
X121657Y1224604D03*
X120999Y1188050D03*
X111999D03*
X102999D03*
X114999Y1210363D03*
X130699Y1210653D03*
X118999Y1219050D03*
X128400Y1188600D03*
X104999Y1231050D03*
X100999Y1231032D03*
X120999Y1228550D03*
X120499Y1264550D03*
X126499D03*
X123938Y1267623D03*
X103499Y1305050D03*
X117149Y1267550D03*
X101500Y1352000D03*
X113500D03*
X113000Y1341000D03*
X102000D03*
X145999Y1353050D03*
X167499Y1389050D03*
X107228Y1330552D03*
X107500Y1340500D03*
X110499Y1365050D03*
X109999Y1355050D03*
X138000Y1359025D03*
X111499Y1311800D03*
X125999Y1315550D03*
X132999Y1319550D03*
X142667Y1319218D03*
X149562Y1315987D03*
X133475Y1331200D03*
X156999Y1397750D03*
X143199Y1412050D03*
X163499Y1433350D03*
X166799Y1409350D03*
X178200Y1393400D03*
X176599Y1447450D03*
X172299Y1465850D03*
X139815Y1454438D03*
X139235Y1460973D03*
X123999Y1473050D03*
X127898Y1462441D03*
X107300Y1438100D03*
X114499Y1432050D03*
X114000Y1425400D03*
X107999Y1448050D03*
X165499Y1453550D03*
X157915Y1420460D03*
X140799Y1435460D03*
X150338Y1453958D03*
X152499Y1462940D03*
X105099Y1459150D03*
X166799Y1487450D03*
X176299Y1500150D03*
X157440Y1490460D03*
X159054Y1476200D03*
X157440Y1500460D03*
Y1520460D03*
Y1530460D03*
X100499Y1479650D03*
X122199Y1476050D03*
X124999Y1616050D03*
Y1620050D03*
Y1629050D03*
Y1633050D03*
X119999Y1629050D03*
X120100Y1633100D03*
X122499Y1668550D03*
Y1672550D03*
X104999Y1708963D03*
X126562Y1670613D03*
X118999Y1670550D03*
X141500Y1715500D03*
X117249Y1712090D03*
X165575Y1676975D03*
X157500Y1797400D03*
X126599Y1789650D03*
X120299Y1796150D03*
X142144Y1801644D03*
X107300Y1746300D03*
X107100Y1736000D03*
X104417Y1791480D03*
X97999Y1815050D03*
X104500Y1813400D03*
X173899Y1813250D03*
X177599Y1866750D03*
X168299Y1879850D03*
X168499Y1855550D03*
X127499Y1889050D03*
X126999Y1882550D03*
X111499Y1877550D03*
Y1882550D03*
X122999Y1883050D03*
X115999Y1882550D03*
X135999Y1881550D03*
X141300Y1866400D03*
X141800Y1860500D03*
X157999Y1840972D03*
X158000Y1825400D03*
X159054Y1881800D03*
X167200Y1868000D03*
X159054Y1855050D03*
X143491Y1856400D03*
X116499Y1877550D03*
X122999Y1889050D03*
X168899Y1960750D03*
X163599Y1892050D03*
X159173Y1935972D03*
X142499Y1905972D03*
X141499Y1895972D03*
X159421Y1925972D03*
X98000Y1987500D03*
X163500D03*
X146000D03*
X128500D03*
X115000Y1987000D03*
X246200Y65800D03*
X246000Y61300D03*
Y56500D03*
Y52100D03*
X245600Y43800D03*
X245500Y39100D03*
X247100Y47900D03*
X189499Y4550D03*
X206999Y5050D03*
X226499D03*
X241999D03*
X261499Y4550D03*
X246000Y70800D03*
X244900Y149100D03*
X244499Y136550D03*
Y122050D03*
X201499Y104550D03*
X245499Y100550D03*
X246499Y86050D03*
Y80550D03*
X229099Y161350D03*
X206899Y171650D03*
X190199Y178650D03*
X197899Y165075D03*
X249800Y248800D03*
X235399Y263350D03*
X201199Y266750D03*
X181299Y267350D03*
X213499Y283864D03*
X187199Y359050D03*
X223799Y365350D03*
X209199Y365050D03*
X181599Y396250D03*
X217599Y396450D03*
X258999Y396650D03*
X213400Y355300D03*
X224998Y357049D03*
X233998Y357549D03*
X239400Y357400D03*
X252935Y319114D03*
X214063Y318114D03*
X231800Y318414D03*
X179700Y425800D03*
X209999Y426150D03*
X237699Y426050D03*
X218499Y474850D03*
X244199Y483350D03*
X224299Y494650D03*
X242099Y511750D03*
X182499Y532550D03*
X244999Y559550D03*
Y545050D03*
X220499Y560050D03*
Y545550D03*
X257499Y530050D03*
Y512550D03*
Y498050D03*
X205300Y508100D03*
X190499Y507513D03*
X257199Y640050D03*
X224999Y613450D03*
X256499Y609050D03*
Y591550D03*
Y577050D03*
X245000Y647000D03*
X244499Y632050D03*
X219999Y647050D03*
Y632550D03*
X207300Y639400D03*
X206499Y623550D03*
Y609050D03*
X181999Y641550D03*
Y624050D03*
Y609550D03*
X244999Y577050D03*
X220499Y577550D03*
X193549Y575875D03*
X199199Y659150D03*
X234200Y668300D03*
X226399Y677550D03*
X212999Y677350D03*
X190399Y689050D03*
X182599Y688350D03*
X246500Y663300D03*
X218800Y668700D03*
X216999Y686550D03*
X213999Y725050D03*
X230849Y726050D03*
X252499D03*
X224099Y770250D03*
X209500Y759000D03*
X208799Y766750D03*
X214799Y774750D03*
X245599Y773450D03*
X234299Y773750D03*
X247099Y795050D03*
X227199D03*
X197099D03*
X254699Y807650D03*
X233799Y806350D03*
X208299Y805350D03*
X198199Y805950D03*
X190699Y778350D03*
X228999Y765550D03*
X218224Y765325D03*
X241600Y765700D03*
X236800Y765800D03*
X244099Y857450D03*
X245199Y878050D03*
X232399Y886550D03*
X252899Y886350D03*
X252399Y838250D03*
X245399Y823550D03*
X217300Y816800D03*
X199000Y815000D03*
X200539Y890300D03*
X198499Y884113D03*
X245399Y907450D03*
X243899Y923650D03*
X242199Y938750D03*
X256199Y916250D03*
X254899Y929250D03*
X253499Y938050D03*
X252499Y948850D03*
X244199Y973250D03*
X225299Y957650D03*
X213999Y958650D03*
X206699Y953050D03*
X203999Y943350D03*
X204699Y929450D03*
X205999Y978250D03*
X256499Y967050D03*
X233499Y966050D03*
X216999Y967550D03*
X198924Y975975D03*
X229562Y904113D03*
X215499Y905550D03*
X254499Y984550D03*
X245899Y995250D03*
X232299Y981950D03*
X206299Y990250D03*
X207299Y1008150D03*
X202100Y1028100D03*
X253999Y1052050D03*
X253499Y1038550D03*
X232499Y1038050D03*
X216499Y1053050D03*
X215999Y1039550D03*
X258999Y1011550D03*
X233999Y1012550D03*
Y997050D03*
X217999Y1012050D03*
X217499Y998550D03*
Y981050D03*
X199499Y1093850D03*
X209900Y1093600D03*
X249499Y1104150D03*
X260349Y1139200D03*
X256000Y1133000D03*
X255000Y1125700D03*
X221300Y1083238D03*
X214499Y1154250D03*
X223099Y1182750D03*
X210199Y1173450D03*
X204199Y1163850D03*
X208199Y1145850D03*
X180400Y1202800D03*
X201600Y1205900D03*
X220999Y1224350D03*
X242199Y1210050D03*
X242599Y1198350D03*
X232599Y1195750D03*
X247899Y1208650D03*
X251999Y1184550D03*
X212499Y1212550D03*
X181700Y1219900D03*
X212499Y1184550D03*
X196499Y1224550D03*
Y1215550D03*
Y1196550D03*
X202199Y1276850D03*
X202899Y1291450D03*
X179500Y1262000D03*
X179800Y1244100D03*
X196399Y1236650D03*
X221599Y1237250D03*
X222299Y1251850D03*
X229899Y1250550D03*
X216300Y1274800D03*
X234299Y1232650D03*
X261199Y1227950D03*
X250900Y1248500D03*
X242900Y1263000D03*
X232799Y1276150D03*
X254899Y1289950D03*
X241399Y1303250D03*
X211499Y1267050D03*
Y1258050D03*
Y1239050D03*
X195499Y1279050D03*
Y1270050D03*
Y1251050D03*
X239099Y1314150D03*
X252399Y1326350D03*
X219099Y1325950D03*
X226599Y1340250D03*
X207699Y1337950D03*
X195500Y1352500D03*
X213199Y1350050D03*
X227399Y1363050D03*
X234300Y1375700D03*
X217499Y1387450D03*
X249800Y1388400D03*
X245999Y1358050D03*
X246499Y1370050D03*
X245999Y1339050D03*
X208049Y1385550D03*
X258999Y1396950D03*
X230599Y1400250D03*
X217999Y1408850D03*
X204699Y1418350D03*
X203199Y1393250D03*
X201000Y1408500D03*
X180599Y1424050D03*
X180000Y1439500D03*
X204999Y1472650D03*
X250199Y1473550D03*
X226300Y1447800D03*
X230899Y1437350D03*
X238899Y1453750D03*
X259299Y1438750D03*
X227999Y1421550D03*
X212400Y1433700D03*
X194200Y1457900D03*
X244999Y1412550D03*
X245499Y1424550D03*
X181500Y1479000D03*
X202399Y1500750D03*
X208999Y1491250D03*
X247500Y1499000D03*
X248000Y1482000D03*
X212899Y1535550D03*
X230999D03*
X213399Y1500300D03*
X236999Y1535550D03*
X232650Y1493450D03*
X246200Y1617600D03*
X239400Y1624300D03*
X218000Y1614300D03*
X209200Y1624000D03*
X228999Y1637550D03*
X211999Y1568550D03*
X238300Y1575100D03*
X231499Y1575050D03*
X224499D03*
X217999Y1574550D03*
X211999D03*
X258700Y1645100D03*
X237400Y1663800D03*
X230600Y1670500D03*
X197600Y1694900D03*
X204400Y1688200D03*
X216601Y1684350D03*
X226800Y1684200D03*
X220100Y1691700D03*
X209901Y1691850D03*
X212000Y1701300D03*
X201801Y1701450D03*
X195001Y1708150D03*
X205200Y1708000D03*
X180701Y1716050D03*
X195500Y1717000D03*
X200600Y1663600D03*
X199900Y1670600D03*
X213000Y1672500D03*
X181900Y1675300D03*
X255699Y1722550D03*
X222700Y1710100D03*
X242999Y1658050D03*
X193499Y1674050D03*
X253999Y1676550D03*
X235499Y1697050D03*
X256499Y1710050D03*
X179999Y1655887D03*
X186000Y1644000D03*
X180000Y1731000D03*
X179701Y1724550D03*
X195000Y1725500D03*
X249199Y1743150D03*
X222499Y1743850D03*
X259499Y1760650D03*
X221499Y1760950D03*
X199699Y1761450D03*
X220799Y1791550D03*
X252199Y1793050D03*
X238699Y1801850D03*
X205199Y1801950D03*
X182299Y1801350D03*
X206900Y1726700D03*
X185999Y1746050D03*
X237999Y1730550D03*
X244999Y1755050D03*
X194049Y1792600D03*
X253899Y1813250D03*
X215299Y1813950D03*
X255999Y1855950D03*
X204399Y1855450D03*
X206999Y1867550D03*
X241199Y1867150D03*
X244700Y1878700D03*
X224800Y1867000D03*
X212399Y1885850D03*
X199599Y1879850D03*
X181099Y1885850D03*
X261499Y1825050D03*
X209999D03*
X192100Y1813500D03*
X228999Y1856050D03*
X236225Y1883125D03*
X241255Y1896055D03*
X205499Y1968650D03*
X183999Y1968150D03*
X190399Y1961250D03*
X207199Y1892850D03*
X191599Y1891550D03*
X238999Y1970550D03*
X232999Y1971050D03*
X227499D03*
X232314Y1890513D03*
X221300Y1971200D03*
X213562Y1926113D03*
X220062Y1931113D03*
X240964Y1934113D03*
X240900Y1979000D03*
X225199Y1978750D03*
X209699D03*
X188199Y1978250D03*
X254500Y1987500D03*
X236500D03*
X216999Y1987550D03*
X199000Y1987500D03*
X183000D03*
X199600Y1974900D03*
X278999Y5050D03*
X292999Y4550D03*
X310499Y5050D03*
X329999D03*
X343499Y60150D03*
X306999Y55450D03*
X311299D03*
X315799Y55350D03*
X296099Y17100D03*
X305099Y17000D03*
X311400Y17100D03*
X317000Y17300D03*
X306100Y126500D03*
X332200Y94200D03*
X283599Y106250D03*
X274700Y131500D03*
X280999Y120050D03*
X291999Y94050D03*
X343799Y204550D03*
X321799Y173950D03*
X343399Y161350D03*
X307199Y205550D03*
X317499Y192950D03*
X331499Y193250D03*
X262699Y208550D03*
X262299Y164050D03*
X280999Y152050D03*
X325499Y249450D03*
X313199Y270350D03*
X313000Y313900D03*
X316999Y312576D03*
X276299Y376050D03*
X299899Y376650D03*
X328799Y372350D03*
X339399Y358050D03*
X289399Y395750D03*
X310999Y396250D03*
X338399Y395650D03*
X313039Y352350D03*
X321900Y364600D03*
X321748Y343299D03*
X298800Y333000D03*
X294500Y339000D03*
X277799Y338599D03*
X266699Y425050D03*
X336099Y417550D03*
X322099Y426850D03*
X338899Y433850D03*
X300899Y431850D03*
X328599Y442250D03*
X291599Y446150D03*
X266199Y472350D03*
X277999Y545350D03*
X329999Y510450D03*
X298599Y501250D03*
X309399Y513450D03*
X321999Y533150D03*
X297599Y519350D03*
X340799Y512050D03*
X341399Y535850D03*
Y558950D03*
X331999Y555050D03*
Y540550D03*
X307499Y555550D03*
Y541050D03*
X281999Y529550D03*
Y512050D03*
Y497550D03*
X321999Y550550D03*
X297499Y551050D03*
X321299Y565250D03*
X296199Y568550D03*
X320799Y582050D03*
X340299Y586550D03*
X342199Y613050D03*
X328599Y602450D03*
X302899Y607950D03*
X328499Y635650D03*
X317999Y627850D03*
X342099Y646350D03*
X280999Y608550D03*
Y591050D03*
Y576550D03*
X331999Y572550D03*
X307499Y573050D03*
X331999Y646550D03*
X307499Y647050D03*
X293999Y630550D03*
Y616050D03*
X269499Y631050D03*
Y616550D03*
X341899Y664950D03*
X342599Y678850D03*
X341399Y715050D03*
X330799Y712450D03*
X324599Y696150D03*
X297699Y681850D03*
X296399Y716950D03*
X308899Y705150D03*
X298399Y703450D03*
X331999Y678550D03*
Y661050D03*
X307499Y679050D03*
Y661550D03*
X293999Y648050D03*
X269499Y648550D03*
X308999Y716450D03*
X315999Y718950D03*
X338099Y811650D03*
X307999Y803150D03*
X307899Y794550D03*
X287799Y794850D03*
X268099Y795450D03*
X275299Y806350D03*
X292999Y743650D03*
X298000Y743500D03*
X323249Y749010D03*
X324959Y766750D03*
X277039Y740300D03*
X315000Y754500D03*
X338599Y821650D03*
X318999Y814350D03*
X338599Y840450D03*
X325599Y823950D03*
X283599Y857450D03*
X293899Y843850D03*
X304899Y856150D03*
X315199Y869450D03*
X323099Y885050D03*
X340099Y887350D03*
X330299Y871850D03*
X323799Y859850D03*
X313499Y847850D03*
X300199Y835250D03*
X288899Y820550D03*
X264999Y858450D03*
X280999Y843050D03*
Y827550D03*
X264999Y842550D03*
X264499Y829050D03*
X297499Y884050D03*
Y868550D03*
X281499Y883550D03*
X280999Y870050D03*
X265799Y901850D03*
X274299Y912950D03*
X310699Y943550D03*
X323499Y956950D03*
X329799Y970650D03*
X331099Y923650D03*
X322099Y913650D03*
X302499Y899050D03*
X321099Y899650D03*
X338399Y901050D03*
X340099Y910350D03*
X340399Y931250D03*
X340099Y952850D03*
X328099Y937250D03*
X315199Y925950D03*
X302199Y914650D03*
X287299Y901050D03*
X269599Y923950D03*
X267199Y935350D03*
X264799Y946850D03*
X263299Y959350D03*
X281099Y943550D03*
X278799Y956150D03*
X277599Y975250D03*
X290099Y948650D03*
X289399Y963350D03*
X288099Y971250D03*
X299399Y965950D03*
X298099Y977250D03*
X307999Y970650D03*
X272999Y965550D03*
X333099Y983450D03*
X285399Y982950D03*
X294699Y989550D03*
X306699Y981250D03*
X304399Y997550D03*
X320999Y997250D03*
X331299Y1017150D03*
X331599Y1028750D03*
X329599Y1040750D03*
X321299Y1012450D03*
Y1024750D03*
X318299Y1038750D03*
X329599Y1057050D03*
X317699Y1054650D03*
X299999Y1052350D03*
X289699Y1021750D03*
X298399Y1008150D03*
X287099Y1000150D03*
X306399Y1020750D03*
X303699Y1038050D03*
X304699Y1057050D03*
X287099Y1035050D03*
X275099Y1024750D03*
X262499Y995850D03*
X269999Y1052550D03*
Y1037050D03*
X274999Y1012050D03*
Y996550D03*
X272999Y981050D03*
X339599Y1081550D03*
X319999Y1066950D03*
X274900Y1115600D03*
X262499Y1129150D03*
X272999Y1102850D03*
X312299Y1093550D03*
X276299Y1134550D03*
X290699Y1122650D03*
X329299Y1098550D03*
X326599Y1112350D03*
X307999Y1142050D03*
X299499Y1113550D03*
Y1098050D03*
X283499Y1113050D03*
X282999Y1099550D03*
X332999Y1138550D03*
Y1123050D03*
X317999Y1137550D03*
X316499Y1124550D03*
X283299Y1144850D03*
X323999Y1153250D03*
X304499Y1156650D03*
X313499Y1170150D03*
X291399Y1174150D03*
X300699Y1185150D03*
X279799Y1191750D03*
X286599Y1203750D03*
X315408Y1202663D03*
X329799Y1182750D03*
X311999Y1213850D03*
X300699Y1227350D03*
X272999Y1214150D03*
X326649Y1218850D03*
X328999Y1200550D03*
X333349Y1307000D03*
X310299Y1240050D03*
X264800Y1261300D03*
X283799Y1249250D03*
X304699Y1265850D03*
X312499Y1280350D03*
X300499Y1305350D03*
X274299Y1276450D03*
X295399Y1292950D03*
X281099Y1302850D03*
X333349Y1288900D03*
Y1270500D03*
X327999Y1255050D03*
X326649Y1227850D03*
X333349Y1332800D03*
X311500Y1316300D03*
X264799Y1313850D03*
X286799Y1326450D03*
X297899Y1336150D03*
X298099Y1357250D03*
X265299Y1339650D03*
X263699Y1359550D03*
X301699Y1377950D03*
X278799Y1386250D03*
X265499Y1376950D03*
X343599Y1360050D03*
X344399Y1338150D03*
X313600Y1391300D03*
X312900Y1366900D03*
X333349Y1363500D03*
X311900Y1344900D03*
X286499Y1364050D03*
Y1345050D03*
X301699Y1395750D03*
X268499Y1453550D03*
X278000Y1422000D03*
X270599Y1408550D03*
X303499Y1411250D03*
X300899Y1433350D03*
X286600Y1449700D03*
X304699Y1457550D03*
X344099Y1449550D03*
Y1421150D03*
Y1393750D03*
X313600Y1442700D03*
X312800Y1467400D03*
X333349Y1429500D03*
X312100Y1420700D03*
X285499Y1418550D03*
Y1427550D03*
Y1399550D03*
X333349Y1393100D03*
Y1481900D03*
X332500Y1519700D03*
X296599Y1497150D03*
X312000Y1514600D03*
X286700Y1516100D03*
X289999Y1554650D03*
X293700Y1553351D03*
X276039Y1551300D03*
X314999Y1527550D03*
X307000Y1619600D03*
X297800Y1561600D03*
X291400Y1561500D03*
X344500Y1583600D03*
X337199Y1636350D03*
X278499Y1621550D03*
X265700Y1635100D03*
X324000Y1562500D03*
X312999Y1566050D03*
X323999Y1577250D03*
X289000Y1641800D03*
X320299Y1642950D03*
X316799Y1657450D03*
X302399Y1662950D03*
X284300Y1676900D03*
X334399Y1691650D03*
X329999Y1716950D03*
X291099Y1707450D03*
X335767Y1662735D03*
X318499Y1675550D03*
X299999Y1696050D03*
X270999Y1660550D03*
X273499Y1694050D03*
X280499Y1718550D03*
X320999Y1706050D03*
X303999Y1722050D03*
X343899Y1752650D03*
X297099Y1733850D03*
X270599Y1748950D03*
X290699Y1760750D03*
X286599Y1791850D03*
X327299D03*
X322299Y1802150D03*
X303999Y1800850D03*
X270599Y1801450D03*
X263499Y1734550D03*
X285499Y1742550D03*
X321999Y1733050D03*
X303499Y1753550D03*
X321499Y1772550D03*
X315499Y1812250D03*
X284299Y1811150D03*
X270299Y1867250D03*
X337499Y1855950D03*
X316999D03*
X298999D03*
X308099Y1880550D03*
X295299Y1870250D03*
X313599Y1889250D03*
Y1870250D03*
X326399Y1876250D03*
X336799Y1888950D03*
Y1869950D03*
X283999Y1856050D03*
X314099Y1901250D03*
X326899Y1907250D03*
X326399Y1895250D03*
X335799Y1916450D03*
X336799Y1897950D03*
X305999Y1913050D03*
X302499Y1922050D03*
X280689Y1942710D03*
X296858Y1956228D03*
X315999Y1958550D03*
X327100Y1966472D03*
X329999Y1952273D03*
X325221Y1927272D03*
X313499Y1919050D03*
X326799Y1977050D03*
X329999Y1987550D03*
X311500Y1987500D03*
X291499Y1987550D03*
X272000Y1987500D03*
X416999Y25050D03*
X417499Y46550D03*
X416999Y63550D03*
X345499Y5050D03*
X364999Y4550D03*
X382499Y5050D03*
X395999Y5550D03*
X413499Y6050D03*
X398799Y36152D03*
X381999Y50150D03*
X386799Y45000D03*
X426000Y93500D03*
X381299Y136750D03*
X389599Y90950D03*
X400499Y134050D03*
Y119550D03*
X363999Y136050D03*
X417499Y79050D03*
Y93550D03*
Y108050D03*
Y125550D03*
X416999Y145050D03*
X357503Y77043D03*
X374499Y77550D03*
X385999Y78050D03*
X401499Y80550D03*
X387599Y220150D03*
X385999Y207250D03*
X354099Y175350D03*
X389299Y161650D03*
X400499Y151550D03*
X363999Y153550D03*
X416999Y164050D03*
X417999Y185050D03*
X423799Y259750D03*
X383299Y310250D03*
X386899Y299250D03*
X359399Y307250D03*
X347399Y301950D03*
X355999Y242750D03*
X347699Y269050D03*
X382999Y276650D03*
X412999Y307550D03*
Y290050D03*
Y275550D03*
X354099Y373050D03*
X368299Y386350D03*
X357999Y359050D03*
X380599Y381050D03*
X386599Y348450D03*
X394899Y357750D03*
X422499Y348150D03*
X422199Y363350D03*
X420199Y391350D03*
X419599Y458550D03*
X426599Y415350D03*
X415099Y422550D03*
X410799Y431150D03*
X354699Y426650D03*
X356399Y451750D03*
X351399Y470750D03*
X358399Y498650D03*
X357399Y521250D03*
Y530550D03*
Y543850D03*
X357999Y559450D03*
X420199Y638550D03*
X427499Y624550D03*
X359399Y576050D03*
Y599650D03*
X360399Y615550D03*
X359699Y627550D03*
X345399Y698950D03*
X358899Y657150D03*
X359399Y669450D03*
X359199Y690650D03*
X357699Y707750D03*
X353999Y787750D03*
X347699Y773450D03*
X355999Y752850D03*
X424999Y766550D03*
X422999Y785050D03*
Y799550D03*
X418799Y896050D03*
Y877050D03*
X422499Y855550D03*
Y836550D03*
X422999Y817050D03*
X374500Y973500D03*
X375000Y939000D03*
Y1034000D03*
X424299Y1034050D03*
X423299Y1013050D03*
Y994050D03*
X373500Y1089500D03*
X419999Y1115550D03*
X409499Y1102550D03*
X416099Y1183550D03*
X415499Y1176050D03*
Y1161550D03*
X419499Y1219550D03*
X377499Y1210050D03*
Y1201050D03*
Y1182050D03*
X420099Y1241550D03*
X419499Y1234050D03*
X376599Y1293950D03*
X376499Y1264550D03*
Y1255550D03*
Y1236550D03*
X424999Y1278550D03*
X425499Y1290550D03*
X424999Y1259550D03*
X416699Y1342650D03*
X416199Y1367550D03*
X375599Y1323350D03*
X374499Y1375550D03*
Y1366550D03*
Y1347550D03*
X423299Y1430350D03*
X426799Y1416050D03*
X422299Y1394950D03*
X425799Y1447950D03*
X427099Y1469150D03*
X376299Y1437650D03*
X373099Y1456550D03*
X373499Y1430050D03*
Y1421050D03*
Y1402050D03*
X414799Y1532350D03*
X424299Y1541350D03*
X374099Y1554550D03*
X374799Y1491250D03*
X415999Y1603250D03*
X416199Y1625250D03*
X425499Y1635050D03*
X418299Y1561250D03*
X351899Y1570850D03*
X350600Y1610900D03*
X349099Y1634550D03*
X376099Y1572850D03*
X375099Y1608250D03*
X377700Y1629000D03*
X414799Y1653750D03*
X414399Y1678350D03*
X414499Y1707250D03*
X374999Y1656750D03*
X377099Y1696350D03*
X380099Y1709650D03*
X351099Y1691150D03*
X352000Y1700400D03*
X427499Y1662050D03*
X417799Y1790850D03*
X387899Y1802850D03*
X359499Y1736850D03*
X376799Y1734050D03*
X393499Y1759550D03*
X376499Y1775550D03*
X357999Y1796050D03*
X410757Y1772872D03*
X393999Y1784550D03*
X422999Y1778550D03*
X367000Y1810000D03*
X414499Y1810450D03*
X355699Y1810750D03*
X426499Y1855450D03*
X406999Y1855950D03*
X391499D03*
X369499D03*
X351999Y1855450D03*
X359999Y1878550D03*
X421399Y1888050D03*
X369799Y1880050D03*
X389499Y1885050D03*
X348999Y1879050D03*
X406499Y1874050D03*
X360000Y1967500D03*
X367299Y1956950D03*
X358999Y1925050D03*
X359999Y1897550D03*
Y1906550D03*
X420399Y1962550D03*
Y1934550D03*
Y1953550D03*
X421399Y1916050D03*
Y1907050D03*
X347699Y1972250D03*
X367999Y1940250D03*
X369199Y1919750D03*
X369999Y1901950D03*
X388499Y1959550D03*
Y1950550D03*
Y1932950D03*
X389499Y1913050D03*
Y1904050D03*
X349499Y1910050D03*
X348499Y1956550D03*
X347999Y1944550D03*
Y1925550D03*
X348999Y1898050D03*
X406999Y1905050D03*
X405999Y1951550D03*
X405499Y1939550D03*
Y1920550D03*
X406499Y1893050D03*
X385099Y1975950D03*
X420799Y1977250D03*
X399299Y1976750D03*
X367299Y1972950D03*
X420500Y1987000D03*
X403500D03*
X364999Y1987050D03*
X382499Y1987550D03*
X345499D03*
X436499Y50350D03*
Y31350D03*
X466799Y64750D03*
X465799Y43750D03*
Y24750D03*
X499999Y64050D03*
X500499Y47050D03*
X499999Y25550D03*
X432999Y6050D03*
X448499D03*
X467999Y5550D03*
X485499Y6050D03*
X498999D03*
X437499Y71350D03*
X442799Y142450D03*
X441799Y121450D03*
Y102450D03*
X471399Y124550D03*
X470399Y103550D03*
Y84550D03*
X473099Y141050D03*
X499999Y145550D03*
X500499Y126050D03*
Y108550D03*
Y79550D03*
Y94050D03*
X502899Y217150D03*
X504199Y193250D03*
X472999Y214550D03*
X483599Y179350D03*
X446799Y205650D03*
X445799Y184650D03*
Y165650D03*
X474099Y181050D03*
X473099Y160050D03*
X449999Y217050D03*
X430499D03*
X499999Y164550D03*
X466399Y304950D03*
X479299Y297250D03*
X437499Y307050D03*
Y289550D03*
Y275050D03*
X498399Y470050D03*
X503699Y419250D03*
X472499Y458050D03*
X468799Y414250D03*
X443199Y440850D03*
X440099Y459250D03*
X431099Y479350D03*
X450300Y404200D03*
X490499Y464050D03*
X490999Y444550D03*
Y427050D03*
Y412550D03*
X454499Y472550D03*
X454999Y438550D03*
X454499Y458050D03*
X453999Y417550D03*
X430099Y551450D03*
X485299Y534550D03*
X508699Y498950D03*
X471499Y493950D03*
X452499Y565050D03*
X491499Y504050D03*
X490499Y483050D03*
X453999Y509550D03*
X454499Y490050D03*
X504499Y598050D03*
Y580550D03*
Y566050D03*
X479999Y598550D03*
Y581050D03*
Y566550D03*
X509999Y640550D03*
X452499Y597050D03*
Y579550D03*
X427999Y597550D03*
Y580050D03*
Y565550D03*
X506599Y711650D03*
X487299Y716950D03*
X451099Y711650D03*
X450399Y672750D03*
X444799Y687350D03*
X509999Y672550D03*
Y655050D03*
X488499Y691050D03*
Y673550D03*
Y659050D03*
X463999Y691550D03*
Y674050D03*
Y659550D03*
X467699Y772750D03*
X468699Y788350D03*
X472999Y736550D03*
X489599Y752450D03*
X490299Y734550D03*
X453399Y807950D03*
X452099Y781450D03*
Y762450D03*
X435299Y795150D03*
Y777650D03*
Y763150D03*
X437299Y744650D03*
X495999Y795050D03*
X475699Y880450D03*
X479599Y847550D03*
X462999Y884050D03*
Y865050D03*
X453399Y826950D03*
X434799Y833650D03*
Y814650D03*
X464499Y896050D03*
X493499Y884050D03*
Y865050D03*
X493999Y845550D03*
Y813550D03*
Y828050D03*
X506899Y919950D03*
Y900950D03*
X443599Y945650D03*
X442599Y924650D03*
Y905650D03*
X486799Y941050D03*
X485799Y920050D03*
Y901050D03*
X461999Y966050D03*
X462499Y946550D03*
Y914550D03*
Y929050D03*
X494099Y1017350D03*
X493099Y996350D03*
X462499Y1043850D03*
X461999Y985050D03*
X474499Y1115050D03*
X491999Y1115550D03*
X454999D03*
X439499D03*
X501499Y1102550D03*
X463999Y1102050D03*
X481499Y1102550D03*
X444499D03*
X428999D03*
X436999Y1142550D03*
Y1128050D03*
X504399Y1132250D03*
X473099Y1144550D03*
X453499Y1140550D03*
X484499Y1085850D03*
X483499Y1064850D03*
X433599Y1085550D03*
X432599Y1064550D03*
X463499Y1083850D03*
X462499Y1062850D03*
X437599Y1150050D03*
X487099Y1218050D03*
X486499Y1210550D03*
Y1196050D03*
X443199Y1224250D03*
X507199Y1224350D03*
X506599Y1202350D03*
Y1216850D03*
X505399Y1153250D03*
X474099Y1165550D03*
X454499Y1161550D03*
X443799Y1274250D03*
Y1246250D03*
Y1265250D03*
X443199Y1238750D03*
X507199Y1252350D03*
Y1243350D03*
X465499Y1284550D03*
Y1293550D03*
Y1265550D03*
X498299Y1323350D03*
X468999Y1323950D03*
X428499Y1325350D03*
X508599Y1370550D03*
X444899Y1377950D03*
X434499Y1360250D03*
X448099Y1341250D03*
X473999Y1342450D03*
X485599Y1367550D03*
X468699Y1362850D03*
X466699Y1378150D03*
X498899Y1386450D03*
X499199Y1350550D03*
X459699Y1468050D03*
X464199Y1401450D03*
X459999Y1424050D03*
X498899Y1408350D03*
X500899Y1434350D03*
X505899Y1466250D03*
X482599Y1449950D03*
X456399Y1445950D03*
X445099Y1464250D03*
X478299Y1464850D03*
X481499Y1417050D03*
Y1402550D03*
X441499Y1431550D03*
Y1414050D03*
Y1399550D03*
X499699Y1538950D03*
X466999Y1530650D03*
X488299Y1531050D03*
X461399Y1541650D03*
X474299Y1544750D03*
X452199Y1550650D03*
X444299Y1532650D03*
X439599Y1552150D03*
X465999Y1603450D03*
X487099Y1606250D03*
X449199Y1579050D03*
X443799Y1612250D03*
X460199Y1632850D03*
X484999Y1636550D03*
X501399Y1634550D03*
X508199Y1610450D03*
X510100Y1579800D03*
X472299Y1572050D03*
X502199Y1566250D03*
X472499Y1620550D03*
Y1611550D03*
X484200Y1579900D03*
X432499Y1617550D03*
X434500Y1579500D03*
X431999Y1605550D03*
X435300Y1715300D03*
X448399Y1699450D03*
X447699Y1682850D03*
X449599Y1656950D03*
X483599Y1662550D03*
X485599Y1694850D03*
X502899Y1709650D03*
X507399Y1683350D03*
X509199Y1660550D03*
X468499Y1712550D03*
X467999Y1687050D03*
Y1696050D03*
Y1668050D03*
X432400Y1680100D03*
X428600Y1691200D03*
X436799Y1772550D03*
X472699Y1792150D03*
X429499Y1748050D03*
X458499Y1742050D03*
X441499Y1758050D03*
X480999Y1756050D03*
X463999Y1772050D03*
X445499Y1792550D03*
X508200Y1758200D03*
X484999Y1779050D03*
X496999Y1799550D03*
X481299Y1811150D03*
X448099Y1809450D03*
X499999Y1854950D03*
X480499Y1855450D03*
X464999D03*
X443999Y1855950D03*
X476199Y1877450D03*
X434299Y1876050D03*
X446999Y1880050D03*
X492999Y1878050D03*
X504799Y1967550D03*
Y1939550D03*
Y1958550D03*
X505799Y1921050D03*
Y1912050D03*
Y1893050D03*
X475199Y1951950D03*
Y1923950D03*
Y1942950D03*
X476199Y1905450D03*
Y1896450D03*
X459299Y1966850D03*
Y1938850D03*
Y1957850D03*
X460299Y1920350D03*
Y1911350D03*
Y1892350D03*
X433299Y1950550D03*
Y1922550D03*
Y1941550D03*
X434299Y1904050D03*
Y1895050D03*
X445999Y1954550D03*
Y1945550D03*
Y1926550D03*
X446999Y1908050D03*
Y1899050D03*
X493499Y1909050D03*
X492499Y1955550D03*
X491999Y1943550D03*
Y1924550D03*
X492999Y1897050D03*
X509299Y1977250D03*
X493799D03*
X473299D03*
X455799Y1976750D03*
X436299Y1977250D03*
X492500Y1987500D03*
X476000Y1987000D03*
X456500Y1987500D03*
X438999Y1987550D03*
X522899Y64350D03*
Y45350D03*
X587999Y63550D03*
X588499Y46550D03*
X587999Y25050D03*
X541499Y63550D03*
X541999Y46550D03*
X541499Y25050D03*
X516499Y6550D03*
X535999D03*
X551499D03*
X570999Y6050D03*
X588499Y6550D03*
X523899Y85350D03*
X520299Y141450D03*
Y122450D03*
X569099Y112550D03*
X568099Y91550D03*
Y72550D03*
X562799Y146750D03*
Y127750D03*
X587999Y145050D03*
X588499Y125550D03*
X541499Y145050D03*
X541999Y125550D03*
Y108050D03*
Y79050D03*
Y93550D03*
X565999Y199950D03*
X528799D03*
X521299Y162450D03*
X563799Y167750D03*
X587999Y217050D03*
X568499Y217550D03*
X552999D03*
X533499D03*
X588999Y185050D03*
X587999Y164050D03*
X542499Y185050D03*
X541499Y164050D03*
X544799Y293950D03*
X540099Y306550D03*
X516899Y306950D03*
X572999Y287050D03*
X572499Y306550D03*
X572999Y269550D03*
Y255050D03*
X579899Y375750D03*
X573499Y346550D03*
X572499Y325550D03*
X577899Y460550D03*
X578399Y441050D03*
X577399Y420050D03*
X539799Y466050D03*
X538799Y445050D03*
X576099Y481850D03*
X511299Y449150D03*
X519499Y471550D03*
X518999Y416550D03*
X592499Y478050D03*
Y459050D03*
X592999Y439550D03*
Y422050D03*
Y407550D03*
X556499Y467550D03*
X555999Y412550D03*
X539299Y485550D03*
X576599Y522350D03*
X577099Y502850D03*
X518999Y508550D03*
X519499Y489050D03*
X555999Y504550D03*
X556499Y485050D03*
X534499Y640050D03*
X586299Y711250D03*
X565699Y710650D03*
X549999Y710050D03*
X547999Y728550D03*
X573499Y690550D03*
Y673050D03*
Y658550D03*
X534499Y672050D03*
Y654550D03*
Y805950D03*
X511199Y782050D03*
X527499Y747150D03*
X525499Y772450D03*
X547499Y799050D03*
Y780050D03*
X547999Y760550D03*
Y743050D03*
X575499Y802050D03*
X575999Y782550D03*
Y765050D03*
X577999Y732050D03*
X575999Y750550D03*
X526499Y851150D03*
X510899Y868150D03*
X578299Y895650D03*
X541399Y873450D03*
Y854450D03*
X512899Y842550D03*
Y823550D03*
X521999Y895550D03*
X522499Y876050D03*
X576499Y842050D03*
X575499Y821050D03*
X583299Y961450D03*
X578299Y914650D03*
X540299Y956850D03*
X539299Y935850D03*
X570899Y965850D03*
Y946850D03*
X521999Y914550D03*
X562999Y898050D03*
X560499Y968050D03*
X560999Y948550D03*
Y916550D03*
Y931050D03*
X516499Y957050D03*
X514499Y975550D03*
X583299Y980450D03*
X534599Y1048550D03*
X571899Y986850D03*
X573499Y1055550D03*
Y1036550D03*
X541899Y1021450D03*
X540899Y1000450D03*
Y981450D03*
X560499Y987050D03*
X560999Y999050D03*
X558999Y1049550D03*
Y1017550D03*
Y1032050D03*
X513999Y1046050D03*
Y1027050D03*
X514499Y1007550D03*
Y990050D03*
X588499Y1101550D03*
X578999Y1114550D03*
X568499Y1101550D03*
X564499Y1116050D03*
X548999D03*
X529499D03*
X511999Y1115550D03*
X553999Y1103050D03*
X538499D03*
X518999D03*
X535599Y1069550D03*
X574499Y1076550D03*
X558499Y1088050D03*
Y1069050D03*
X547099Y1202750D03*
Y1221750D03*
X546499Y1180750D03*
Y1195250D03*
X567999Y1215550D03*
Y1206550D03*
Y1187550D03*
X527999Y1212550D03*
X527499Y1200550D03*
Y1181550D03*
X579299Y1300750D03*
X527499Y1278150D03*
X530499Y1297050D03*
X561099Y1301050D03*
X566399Y1273850D03*
X549399Y1302850D03*
Y1274850D03*
Y1293850D03*
X548799Y1252850D03*
Y1267350D03*
X547099Y1230750D03*
X583299Y1283250D03*
Y1255250D03*
Y1274250D03*
X582699Y1233250D03*
Y1247750D03*
X565999Y1248550D03*
Y1234050D03*
X525999Y1263050D03*
Y1245550D03*
Y1231050D03*
X555699Y1322950D03*
X581999Y1370150D03*
X559099Y1343250D03*
X545099Y1355250D03*
X518499Y1346950D03*
X540399Y1382150D03*
X523999Y1391050D03*
X523499Y1360050D03*
Y1379050D03*
X580999Y1412750D03*
X575699Y1438950D03*
X538799Y1409750D03*
X536799Y1436350D03*
X528499Y1460250D03*
X546099Y1467550D03*
X582999Y1461250D03*
X557499Y1443050D03*
Y1452050D03*
Y1424050D03*
X516999Y1437050D03*
X517499Y1449050D03*
X516999Y1418050D03*
X590599Y1483450D03*
X529799Y1555050D03*
X567999Y1549950D03*
X582299Y1534150D03*
X538999Y1528350D03*
X518899Y1530150D03*
X532499Y1635550D03*
X552099Y1601950D03*
X553399Y1624550D03*
X590799Y1627850D03*
X588000Y1604000D03*
X588099Y1572050D03*
X552199Y1576650D03*
X569499Y1619550D03*
Y1610550D03*
X573400Y1577600D03*
X529499Y1616550D03*
X533800Y1575500D03*
X528999Y1604550D03*
X518499Y1643950D03*
X538299Y1721050D03*
X532599Y1655650D03*
X554199Y1651950D03*
X555199Y1674750D03*
X555399Y1689350D03*
X555899Y1706750D03*
X580299Y1722550D03*
X590599Y1694450D03*
X580799Y1646150D03*
X572999Y1694550D03*
Y1703550D03*
Y1675550D03*
X532499Y1688550D03*
X532999Y1700550D03*
X532499Y1669550D03*
X582599Y1740050D03*
X560399Y1792550D03*
X555500Y1802700D03*
X539499Y1788150D03*
X526499Y1801150D03*
X556199Y1727050D03*
X522300Y1739200D03*
X532499Y1763050D03*
X515499Y1779050D03*
X531799Y1818450D03*
X514199Y1815750D03*
X591499Y1855950D03*
X573999Y1855450D03*
X554499Y1855950D03*
X538999D03*
X517499Y1855450D03*
X588899Y1882350D03*
X562599Y1874450D03*
X519399Y1876750D03*
X533499Y1884050D03*
X575999Y1888050D03*
X587899Y1956850D03*
Y1928850D03*
Y1947850D03*
X588899Y1910350D03*
Y1901350D03*
X561599Y1948950D03*
Y1920950D03*
Y1939950D03*
X562599Y1902450D03*
Y1893450D03*
X546999Y1966850D03*
Y1938850D03*
Y1957850D03*
X547999Y1920350D03*
Y1911350D03*
Y1892350D03*
X518399Y1951250D03*
Y1923250D03*
Y1942250D03*
X519399Y1904750D03*
Y1895750D03*
X532499Y1958550D03*
Y1949550D03*
Y1930550D03*
X533499Y1912050D03*
Y1903050D03*
X575999Y1907050D03*
X576499Y1919050D03*
X574999Y1953550D03*
X575499Y1965550D03*
X574999Y1934550D03*
X585799Y1976250D03*
X570299D03*
X546299Y1977250D03*
X528799Y1976750D03*
X568999Y1987050D03*
X553499D03*
X588499Y1986550D03*
X511999Y1987550D03*
X531500Y1987500D03*
X603999Y54350D03*
Y35350D03*
X651799Y59650D03*
Y40650D03*
X674999Y59050D03*
X675499Y42050D03*
X674999Y20550D03*
X624499Y61550D03*
X624999Y44550D03*
X624499Y23050D03*
X608499Y6550D03*
X625999Y7050D03*
X645499D03*
X660999D03*
X604999Y75350D03*
X603999Y133750D03*
X652799Y80650D03*
X649899Y138350D03*
X674999Y140550D03*
X675499Y121050D03*
Y103550D03*
Y74550D03*
Y89050D03*
X624499Y143050D03*
X624999Y123550D03*
X623899Y202550D03*
X604999Y173750D03*
X603999Y152750D03*
X650899Y178350D03*
X649899Y157350D03*
X662499Y218050D03*
X642999D03*
X625499Y217550D03*
X605499D03*
X675999Y180550D03*
X674999Y159550D03*
X625499Y183050D03*
X624499Y162050D03*
X656499Y307050D03*
X653999Y286550D03*
X627999Y280050D03*
X627499Y299550D03*
X627999Y262550D03*
Y248050D03*
X599799Y385150D03*
X600299Y365650D03*
X599299Y344650D03*
X659899Y363250D03*
X632399Y358750D03*
X635399Y376250D03*
X607399Y380250D03*
X643599Y395950D03*
X655999Y344050D03*
X656499Y324550D03*
X628499Y339550D03*
X628200Y320000D03*
X644099Y450950D03*
X644599Y416950D03*
X644099Y436450D03*
X621499Y466550D03*
X621999Y432550D03*
X621499Y452050D03*
X620999Y411550D03*
X666999Y476550D03*
X643499Y546750D03*
X642499Y525750D03*
X613700Y504600D03*
X621499Y484050D03*
X593499Y499050D03*
X666499Y547050D03*
X666999Y508550D03*
X666499Y528050D03*
X666999Y491050D03*
X642999Y566250D03*
X640599Y604650D03*
X673999Y645150D03*
X645099Y639150D03*
X631999Y639650D03*
X665999Y623550D03*
X620499D03*
Y609050D03*
X595999Y641550D03*
Y624050D03*
Y609550D03*
X667499Y568050D03*
X651999Y718350D03*
X648999Y702350D03*
X629099Y714050D03*
X605299Y661750D03*
X609499Y708050D03*
X607499Y726550D03*
X647499Y689050D03*
Y671550D03*
Y657050D03*
X622999Y689550D03*
Y672050D03*
X597999Y690050D03*
X647399Y742150D03*
X653099Y803350D03*
X621499Y767150D03*
X633499Y750150D03*
X606999Y797050D03*
Y778050D03*
X607499Y758550D03*
Y741050D03*
X664999Y805050D03*
Y786050D03*
X665499Y766550D03*
X645799Y816650D03*
X642599Y883250D03*
X641599Y862250D03*
Y843250D03*
X621999Y835050D03*
X612999Y854550D03*
X629499Y853050D03*
Y868550D03*
X613499Y868050D03*
X663499Y896050D03*
X663999Y876550D03*
Y844550D03*
Y859050D03*
X665999Y826050D03*
X639499Y971150D03*
Y952150D03*
X616699Y967250D03*
Y948250D03*
X658999Y959050D03*
X656999Y977550D03*
X603499Y904050D03*
X601499Y954550D03*
Y922550D03*
Y937050D03*
X664499Y936050D03*
X663499Y915050D03*
X673999Y1036550D03*
Y1017550D03*
X674699Y1061450D03*
X611399Y1045650D03*
Y1026650D03*
X617699Y988250D03*
X656499Y1048050D03*
Y1029050D03*
X656999Y1009550D03*
Y992050D03*
X631999Y1001550D03*
X629999Y1052050D03*
Y1020050D03*
Y1034550D03*
X600999Y1002050D03*
X598999Y1052550D03*
Y1020550D03*
Y1035050D03*
X633999Y1103050D03*
X669499Y1116550D03*
X616499Y1115050D03*
X605999Y1102050D03*
X598999Y1114550D03*
X674699Y1080450D03*
X674999Y1134950D03*
X641799Y1137650D03*
X627699Y1143550D03*
X612399Y1066650D03*
X629499Y1090550D03*
Y1071550D03*
X598499Y1091050D03*
Y1072050D03*
X603899Y1157850D03*
X626199Y1183450D03*
X597599Y1196050D03*
X596599Y1215050D03*
X651599Y1203050D03*
X650599Y1182050D03*
X651299Y1174150D03*
X650299Y1153150D03*
X668199Y1173850D03*
X667199Y1152850D03*
X671199Y1213750D03*
X670199Y1192750D03*
X628699Y1164550D03*
X668699Y1227650D03*
X672999Y1303450D03*
X608899Y1305050D03*
X600899Y1238650D03*
X630499Y1243950D03*
X657099Y1272850D03*
X657799Y1288450D03*
X656399Y1307050D03*
X618199Y1296250D03*
Y1268250D03*
Y1287250D03*
X617599Y1246250D03*
Y1260750D03*
X638999Y1286550D03*
Y1295550D03*
Y1267550D03*
X598499Y1280550D03*
X598999Y1292550D03*
X598499Y1261550D03*
X671999Y1324950D03*
X631799Y1322650D03*
X605599Y1326350D03*
X665699Y1337250D03*
X606199Y1338250D03*
X617899Y1360850D03*
X625499Y1383450D03*
X632499Y1347950D03*
X599999Y1382550D03*
X599499Y1351550D03*
Y1370550D03*
X654999Y1385050D03*
X654499Y1373050D03*
Y1354050D03*
X659699Y1445950D03*
X604899Y1407750D03*
X601299Y1447650D03*
X636799Y1461250D03*
X626799Y1432350D03*
X627499Y1406050D03*
X665699Y1462250D03*
X652999Y1435550D03*
Y1418050D03*
Y1403550D03*
X656099Y1479550D03*
X625199Y1489150D03*
X610899Y1496750D03*
X672399Y1508750D03*
X673699Y1535350D03*
X662099Y1549650D03*
X643099Y1541350D03*
X599799Y1544650D03*
X617699Y1530350D03*
X670699Y1603150D03*
X671399Y1625350D03*
X628499Y1636650D03*
X633499Y1615450D03*
X635500Y1603900D03*
X652399Y1575850D03*
X623499Y1564050D03*
X652499Y1618550D03*
Y1609550D03*
X639200Y1576200D03*
X612499Y1615550D03*
X611900Y1577900D03*
X611999Y1603550D03*
X649399Y1644950D03*
X657099Y1668850D03*
X635099Y1691150D03*
X607599Y1716450D03*
X593399Y1668850D03*
X627299Y1659550D03*
X600599Y1645450D03*
X674999Y1676550D03*
X656499Y1697050D03*
X609499Y1692050D03*
Y1675050D03*
X642499Y1709050D03*
X665399Y1752350D03*
X650399Y1771250D03*
X593299Y1760950D03*
X619499Y1803150D03*
X627273Y1793905D03*
X606999Y1745550D03*
X625499Y1725050D03*
X675499Y1757050D03*
X675999Y1769050D03*
X675499Y1738050D03*
X642400Y1800100D03*
X659159Y1792278D03*
X626999Y1800050D03*
X645099Y1877550D03*
X667999Y1870950D03*
X632799Y1820450D03*
X627494Y1829068D03*
X608599Y1810750D03*
X669399Y1855350D03*
X627499Y1855950D03*
X611999D03*
X630699Y1872750D03*
X602799Y1887350D03*
X640999Y1815550D03*
X595199Y1820910D03*
X659549Y1815384D03*
X644049Y1810834D03*
X659549Y1810634D03*
X646799Y1926450D03*
X645399Y1906150D03*
X673899Y1966850D03*
Y1938850D03*
Y1957850D03*
X674899Y1920350D03*
Y1911350D03*
Y1892350D03*
X660299Y1964550D03*
Y1936550D03*
Y1955550D03*
X661299Y1918050D03*
Y1909050D03*
Y1890050D03*
X629699Y1947250D03*
Y1919250D03*
Y1938250D03*
X630699Y1900750D03*
Y1891750D03*
X601799Y1961850D03*
Y1933850D03*
Y1952850D03*
X602799Y1915350D03*
Y1906350D03*
X616499Y1913050D03*
Y1922050D03*
Y1894050D03*
X615499Y1959550D03*
Y1968550D03*
Y1940550D03*
X644999Y1953050D03*
X645499Y1965050D03*
X644999Y1934050D03*
X659299Y1976250D03*
X643799D03*
X622799D03*
X605299Y1975750D03*
X642499Y1987050D03*
X626999D03*
X661999Y1986550D03*
X605999Y1987050D03*
X751499Y48350D03*
X694999Y62650D03*
X757499Y63050D03*
Y44050D03*
X725499Y62050D03*
X725999Y45050D03*
X725499Y23550D03*
X680499Y6550D03*
X697999Y7050D03*
X712499Y6050D03*
X729999Y6550D03*
X749499D03*
X752099Y112150D03*
X738199Y137450D03*
X695999Y102650D03*
X694999Y81650D03*
X699699Y141750D03*
X758499Y84050D03*
X725499Y143550D03*
X725999Y124050D03*
Y106550D03*
Y77550D03*
Y92050D03*
X728899Y204550D03*
X688999Y196550D03*
X700699Y181750D03*
X699699Y160750D03*
X749499Y218550D03*
X729499D03*
X711999Y218050D03*
X677999D03*
X726499Y183550D03*
X725499Y162550D03*
X711999Y307550D03*
Y293050D03*
X723200Y275500D03*
X711499Y252550D03*
X680500Y280700D03*
X682999Y300050D03*
X683499Y263050D03*
Y248550D03*
X749899Y398550D03*
X711499Y344550D03*
X711999Y325050D03*
X683999Y340050D03*
X682999Y319050D03*
X713699Y455450D03*
X713199Y474950D03*
X712699Y434450D03*
X750399Y453550D03*
X750899Y419550D03*
X750399Y439050D03*
X694999Y480550D03*
X737999Y467050D03*
X691399Y548350D03*
X755699Y528650D03*
X756199Y509150D03*
X755199Y488150D03*
X754499Y564650D03*
X713099Y561550D03*
X713599Y542050D03*
X712599Y521050D03*
X713199Y489450D03*
X695499Y521050D03*
X695999Y501550D03*
X737999Y559050D03*
X738499Y539550D03*
Y522050D03*
Y507550D03*
X738999Y488050D03*
X691899Y588850D03*
X692399Y569350D03*
X754999Y605150D03*
X755499Y585650D03*
X717099Y636050D03*
X729699Y640350D03*
X731499Y604050D03*
Y586550D03*
Y572050D03*
X690499Y623050D03*
X720899Y712250D03*
X732499Y729250D03*
X681899Y713650D03*
X679299Y703050D03*
X727099Y715050D03*
X739399Y688150D03*
X747999Y670750D03*
X723499Y654850D03*
X693999Y648150D03*
X754999Y694050D03*
X702999Y688050D03*
Y670550D03*
Y656050D03*
X678499Y688550D03*
Y671050D03*
X749999Y700050D03*
X710899Y751150D03*
X696299Y741850D03*
X685999Y780050D03*
X694599Y763450D03*
X743099Y785350D03*
X733799Y761450D03*
X716599Y736850D03*
X723999Y802350D03*
Y783350D03*
X687099Y804650D03*
X706999Y811550D03*
Y792550D03*
X707499Y773050D03*
X757499Y745342D03*
X728499Y841850D03*
X724999Y823350D03*
X688099Y844650D03*
X687099Y823650D03*
X729999Y881850D03*
Y862850D03*
X751599Y887350D03*
X705999Y851050D03*
Y865550D03*
X707999Y832550D03*
X751499Y855550D03*
Y836550D03*
X751999Y817050D03*
X707399Y918550D03*
Y899550D03*
X678299Y978350D03*
X730999Y902850D03*
X688099Y936350D03*
X687099Y915350D03*
Y896350D03*
X724699Y976250D03*
X723699Y955250D03*
Y936250D03*
X752599Y927350D03*
X751599Y906350D03*
X706499Y942550D03*
X749999Y965550D03*
Y946550D03*
X751399Y1023550D03*
Y1004550D03*
X752399Y1052550D03*
X734999Y1030550D03*
Y1045050D03*
X713999Y1049050D03*
Y1031550D03*
Y1017050D03*
X678299Y997350D03*
X694999Y993050D03*
X692999Y1043550D03*
Y1011550D03*
Y1026050D03*
X750999Y986550D03*
X734999Y1062550D03*
X713499Y1068550D03*
X737999Y1119050D03*
X727499Y1106050D03*
X720499Y1118550D03*
X709999Y1105550D03*
X700499Y1118550D03*
X689999Y1105550D03*
X727499Y1132650D03*
X704299D03*
X692499Y1082050D03*
Y1063050D03*
X753999Y1100050D03*
X713599Y1214650D03*
X756799Y1217650D03*
X758799Y1190150D03*
Y1199150D03*
X717999Y1169150D03*
X716999Y1148150D03*
X714399Y1199750D03*
X713399Y1178750D03*
X735999Y1220550D03*
Y1206050D03*
X737999Y1187550D03*
Y1178550D03*
Y1159550D03*
X695999Y1217550D03*
Y1203050D03*
X697999Y1184550D03*
X697499Y1172550D03*
Y1153550D03*
X755600Y1149800D03*
X684299Y1249550D03*
X740799Y1298750D03*
X723499Y1292650D03*
Y1278150D03*
X725499Y1250650D03*
Y1259650D03*
Y1231650D03*
X755399Y1300650D03*
Y1286150D03*
X757399Y1258650D03*
Y1267650D03*
Y1239650D03*
X756799Y1232150D03*
X709699Y1264550D03*
X708699Y1243550D03*
X740499Y1252550D03*
Y1270050D03*
X695999Y1235050D03*
X758499Y1371050D03*
X739199Y1348950D03*
X742099Y1320650D03*
X719199Y1322350D03*
X695999Y1323350D03*
X677999Y1347550D03*
X680299Y1365850D03*
X713899Y1386450D03*
X707899Y1346250D03*
X734199Y1373850D03*
X694999Y1388050D03*
Y1379050D03*
Y1360050D03*
X702299Y1404450D03*
X736199Y1399050D03*
X741099Y1450250D03*
X737799Y1428350D03*
X716899Y1459850D03*
X700899Y1450250D03*
X681299Y1393150D03*
X678299Y1425050D03*
X686999Y1468850D03*
X719499Y1446650D03*
X721899Y1419050D03*
X754999Y1420050D03*
Y1437550D03*
X692999Y1421050D03*
Y1406550D03*
X741099Y1498150D03*
X729199Y1492750D03*
X716199Y1503050D03*
X735799Y1533650D03*
X714599Y1533950D03*
X708899Y1549250D03*
X685299Y1551950D03*
X747199Y1509150D03*
X755499Y1507550D03*
X754000Y1551000D03*
X734499Y1563550D03*
X722199Y1564250D03*
X706700Y1579900D03*
X698599Y1568550D03*
X681299Y1579150D03*
X693599Y1602450D03*
X686699Y1638650D03*
X742000Y1560000D03*
X743400Y1578700D03*
X719999Y1605050D03*
X751300Y1604900D03*
X732999Y1620050D03*
X756299Y1679050D03*
X738799Y1677250D03*
X750099Y1694950D03*
X756499Y1712150D03*
X739199Y1716750D03*
X721199Y1723750D03*
X727399Y1694350D03*
X717099Y1702450D03*
X693099Y1722350D03*
X691999Y1660550D03*
X751899Y1752150D03*
X747799Y1766750D03*
X729499Y1778750D03*
X729999Y1756450D03*
X747499Y1734350D03*
X702599Y1730550D03*
X709099Y1751850D03*
X690499Y1744950D03*
X694599Y1768450D03*
X690249Y1805634D03*
X715999Y1763050D03*
Y1772050D03*
Y1744050D03*
X693549Y1793134D03*
X706549Y1793634D03*
X744049Y1791634D03*
X740549Y1802634D03*
X753949Y1798194D03*
X705000Y1811900D03*
X755000Y1825000D03*
X686999Y1870250D03*
X728099Y1844750D03*
X747599Y1844250D03*
X743799Y1888850D03*
X728299D03*
X753699Y1879250D03*
X732199Y1878750D03*
X744699Y1868450D03*
X758399Y1868350D03*
X723199Y1867950D03*
X743399Y1855850D03*
X725899Y1855350D03*
X690899Y1855850D03*
X706399D03*
X697999Y1844550D03*
X732999Y1868550D03*
X711500Y1817700D03*
X704300Y1828400D03*
X686473Y1818375D03*
X740549Y1810384D03*
X696299Y1898850D03*
X716599Y1918450D03*
X728799Y1933050D03*
X709199Y1962950D03*
X698299Y1948050D03*
X676399Y1901150D03*
X695299Y1926450D03*
X711899Y1944050D03*
X736799Y1919450D03*
X728799Y1908150D03*
X705599Y1891850D03*
X730499Y1954650D03*
X755299Y1902150D03*
X739799D03*
X685499Y1959050D03*
Y1968050D03*
Y1940050D03*
X755500Y1914500D03*
X752500Y1954500D03*
X721499Y1974550D03*
X696299Y1976250D03*
X678799Y1975750D03*
X754999Y1987550D03*
X737499Y1987050D03*
X717999Y1987550D03*
X702499D03*
X679499Y1987050D03*
X774399Y54050D03*
X763399Y24150D03*
X817599Y43750D03*
X824899Y25150D03*
X813299Y68350D03*
Y49350D03*
X796999Y65550D03*
X797499Y48550D03*
X796999Y27050D03*
X764999Y6550D03*
X784499Y6050D03*
X801999Y6550D03*
X818999Y6050D03*
X836499Y6550D03*
X778399Y105250D03*
X775399Y80250D03*
X821199Y137450D03*
X813299Y110850D03*
X805899Y126150D03*
X767399Y140150D03*
X796599Y123450D03*
X814299Y89350D03*
X796999Y147050D03*
X797499Y127550D03*
Y110050D03*
Y81050D03*
Y95550D03*
X837499Y138550D03*
X838499Y145050D03*
X760799Y181950D03*
X779399Y200550D03*
X786499Y219050D03*
X800999Y216550D03*
X766999Y219050D03*
X797999Y187050D03*
X796999Y166050D03*
X821999Y193116D03*
X827499Y163550D03*
X820749Y163850D03*
X813249Y163800D03*
X839249Y164050D03*
X770999Y302050D03*
X785499Y291050D03*
X770999Y290050D03*
Y295550D03*
X827499Y313424D03*
X763571Y295622D03*
X777999Y296050D03*
X786978Y298529D03*
X836500Y274950D03*
X812500Y282750D03*
X839299Y390950D03*
X819299Y394250D03*
X838499Y352050D03*
X758778Y345000D03*
X768178Y333964D03*
X784499Y334050D03*
X840299Y430950D03*
X839299Y409950D03*
X820299Y434250D03*
X819299Y413250D03*
X802999Y466050D03*
X774999Y476550D03*
Y462050D03*
X825399Y540950D03*
X825899Y521450D03*
X824899Y500450D03*
X835599Y564050D03*
X834599Y543050D03*
X802999Y558050D03*
X803499Y538550D03*
Y521050D03*
Y506550D03*
X803999Y487050D03*
X775499Y553550D03*
X774499Y532550D03*
X774999Y494050D03*
X774499Y513550D03*
X835099Y583550D03*
X814499Y601550D03*
Y584050D03*
Y569550D03*
X789999Y602050D03*
Y584550D03*
Y570050D03*
X835150Y677650D03*
X764599Y655750D03*
X766499Y699050D03*
X782999Y699550D03*
X836149Y714050D03*
X766499Y705550D03*
X806500Y687250D03*
X778999Y806950D03*
X763099Y796350D03*
X835999Y799050D03*
Y781550D03*
Y767050D03*
X811499Y799550D03*
Y782050D03*
Y767550D03*
X837799Y754150D03*
X766499Y732842D03*
X762500Y734000D03*
X784939Y733550D03*
X825199Y850850D03*
X827699Y892450D03*
Y873450D03*
X776199Y879250D03*
X775199Y858250D03*
Y839250D03*
X800999Y892550D03*
X802999Y874050D03*
X801999Y853050D03*
Y834050D03*
X802499Y814550D03*
X828699Y913450D03*
X826999Y963150D03*
X773199Y960650D03*
X772199Y939650D03*
Y920650D03*
X800499Y944050D03*
Y963050D03*
X800999Y924550D03*
Y907050D03*
Y1037550D03*
Y1005550D03*
Y1020050D03*
X827999Y1003150D03*
X826999Y982150D03*
X777899Y1028050D03*
X776899Y1007050D03*
Y988050D03*
X801499Y984050D03*
X783999Y1096550D03*
X760999Y1095550D03*
X789499Y1099550D03*
X773499Y1101050D03*
X769499D03*
X773499Y1105050D03*
X769499D03*
X836149Y1118550D03*
X767083Y1134550D03*
X764549Y1138500D03*
X784439Y1136550D03*
X814000Y1087000D03*
X808299Y1175850D03*
X806599Y1189750D03*
X803599Y1211050D03*
X831499Y1209550D03*
Y1200550D03*
Y1181550D03*
X789499Y1225050D03*
X791499Y1206550D03*
X790999Y1194550D03*
Y1175550D03*
X839999Y1157550D03*
X826199Y1294450D03*
X828199Y1267850D03*
X788999Y1278150D03*
X791999Y1294450D03*
X808199Y1290350D03*
Y1275850D03*
X810199Y1248350D03*
Y1257350D03*
Y1229350D03*
X829499Y1242550D03*
Y1228050D03*
X789499Y1257050D03*
Y1239550D03*
X825500Y1379000D03*
X831499Y1324950D03*
X795299Y1326650D03*
X822199Y1335250D03*
X819199Y1353550D03*
X798299Y1344250D03*
X779399Y1361850D03*
X762499Y1335550D03*
Y1353050D03*
X799999Y1340550D03*
Y1358050D03*
X806499Y1390550D03*
X803299Y1426650D03*
X773999Y1393450D03*
X763399Y1401450D03*
X781999Y1434650D03*
X805899Y1464250D03*
X771399Y1474550D03*
X806499Y1408050D03*
X834499Y1397550D03*
X836600Y1416500D03*
X769300Y1488100D03*
X779000Y1488400D03*
X786500Y1488600D03*
X801300Y1489000D03*
X836625Y1487400D03*
X770999Y1500050D03*
X780499D03*
X839499Y1523550D03*
X773499Y1509050D03*
X769499D03*
X786999Y1506550D03*
X771225Y1539474D03*
X767936Y1540336D03*
X784577Y1535628D03*
X812550Y1494050D03*
X813300Y1604100D03*
X827199Y1622750D03*
X841499Y1638950D03*
X803599Y1618350D03*
X826499Y1609050D03*
X825999Y1578050D03*
X839899Y1562050D03*
X829200Y1719800D03*
X824100Y1719900D03*
X819400Y1721900D03*
X837199Y1660550D03*
X814599Y1642650D03*
X776999Y1647650D03*
X797299Y1646650D03*
X802899Y1670550D03*
X839199Y1683550D03*
X808899Y1698450D03*
X779999Y1717050D03*
X770399Y1699650D03*
X765099Y1664950D03*
X823499Y1693050D03*
Y1702050D03*
Y1674050D03*
X782999Y1687050D03*
X783499Y1699050D03*
X782999Y1668050D03*
X788000Y1788000D03*
X774500D03*
X812000Y1799500D03*
X819200Y1727100D03*
X808299Y1755250D03*
X794499Y1734550D03*
X770099Y1730350D03*
X779899Y1748150D03*
X787900Y1758800D03*
X765600Y1756800D03*
X821249Y1791250D03*
X811000Y1793000D03*
X827999Y1791550D03*
X829799Y1856350D03*
X809299D03*
X791799Y1855850D03*
X801099Y1844750D03*
X785599D03*
X765099D03*
X780799Y1888850D03*
X763299Y1888350D03*
X833100Y1878500D03*
X806199Y1879250D03*
X788699Y1878750D03*
X769199Y1879250D03*
X833199Y1868450D03*
X818900Y1870800D03*
X797199Y1868450D03*
X779699Y1867950D03*
X779399Y1855850D03*
X763899D03*
X770999Y1820550D03*
X822499Y1815164D03*
X791999Y1819050D03*
X783499Y1827050D03*
Y1907050D03*
X774499Y1908050D03*
X765999D03*
X838999Y1928550D03*
X790499Y1913050D03*
X775999Y1916050D03*
X840999Y1970550D03*
X767999Y1945173D03*
X764908Y1946592D03*
X768499Y1917550D03*
X785939Y1946800D03*
X812500Y1898500D03*
X813599Y1979950D03*
X789299Y1983850D03*
X829499Y1980250D03*
X829999Y1987550D03*
X812499Y1987050D03*
X792999Y1987550D03*
X777499D03*
X919800Y54600D03*
X844799Y19850D03*
X860799Y24150D03*
X885999Y21150D03*
X855999Y6550D03*
X871499D03*
X890999Y6050D03*
X908499Y6550D03*
X923999Y6050D03*
X924200Y69800D03*
X898800Y96000D03*
X890700Y132500D03*
X872100Y132700D03*
X854300Y132600D03*
X855500Y149500D03*
X873000Y148500D03*
X846500Y149500D03*
X891999Y146050D03*
X841499Y135550D03*
X861999Y146550D03*
X882499Y147050D03*
X896999Y141550D03*
X916499Y115050D03*
X906999Y224150D03*
X887400Y233555D03*
X871786Y233924D03*
Y218924D03*
Y203924D03*
X907999Y264150D03*
X906999Y243150D03*
X906399Y314250D03*
Y295250D03*
X847500Y246600D03*
X850999Y246550D03*
X874700Y244900D03*
X874900Y238600D03*
X871999Y283924D03*
X887400Y259700D03*
X879878Y247724D03*
X886200Y313924D03*
X886600Y303924D03*
X872136Y273924D03*
X858478Y274050D03*
X907399Y335250D03*
X875799Y386250D03*
X904999Y385050D03*
Y370550D03*
X854499Y387550D03*
Y373050D03*
X858400Y352300D03*
X847999Y352550D03*
X870600Y346700D03*
X876799Y426250D03*
X875799Y405250D03*
X884399Y462450D03*
Y443450D03*
X905499Y462050D03*
X904499Y441050D03*
Y422050D03*
X904999Y402550D03*
X854999Y464550D03*
X853999Y443550D03*
X854499Y405050D03*
X853999Y424550D03*
X861199Y546050D03*
X860199Y525050D03*
X885399Y483450D03*
X914699Y524650D03*
X913699Y503650D03*
Y484650D03*
X860699Y565550D03*
X898999Y622050D03*
Y604550D03*
X860499Y607550D03*
X861800Y591200D03*
X918999Y641550D03*
X875100Y644400D03*
X922049Y574375D03*
X870719Y609705D03*
X894000Y642400D03*
X870719Y639705D03*
X870773Y624705D03*
X895999Y720050D03*
Y702550D03*
X900999Y670050D03*
Y652550D03*
X918499Y712050D03*
X918999Y673550D03*
X918499Y693050D03*
X918999Y656050D03*
X875300Y650500D03*
X851300Y651700D03*
X847600Y651600D03*
X887401Y665000D03*
X881200Y652100D03*
X859999Y713050D03*
X871385Y719436D03*
X871786Y709482D03*
X871499Y689436D03*
X871786Y679436D03*
X860796Y678632D03*
X921399Y796350D03*
X921899Y776850D03*
Y759350D03*
Y744850D03*
X884499Y799050D03*
Y781550D03*
Y767050D03*
X859999Y799550D03*
Y782050D03*
Y767550D03*
X919499Y733050D03*
X856299Y753150D03*
X846799Y754150D03*
X865000Y752100D03*
X889699Y876050D03*
X847799Y828250D03*
X857099Y873450D03*
X920399Y886850D03*
Y869350D03*
Y854850D03*
X922399Y836350D03*
X921399Y815350D03*
X898499Y862050D03*
Y844550D03*
Y830050D03*
X873999Y862550D03*
Y845050D03*
Y830550D03*
X886999Y947250D03*
Y907350D03*
X867199Y941350D03*
X866199Y920350D03*
Y901350D03*
X850999Y962550D03*
Y943550D03*
X919899Y925350D03*
X920899Y946350D03*
X919899Y906350D03*
X922049Y978575D03*
X851999Y983550D03*
X921499Y1031050D03*
X920999Y1050550D03*
X921499Y1013550D03*
Y999050D03*
X847500Y1057800D03*
X851000Y1058000D03*
X874733Y1055792D03*
X874999Y1049550D03*
X870468Y1030227D03*
X880033Y1058592D03*
X886919Y1044478D03*
X870298Y1045227D03*
X870777Y1014948D03*
X921999Y1090550D03*
X920999Y1069550D03*
X887400Y1070600D03*
X859999Y1118550D03*
X841999D03*
X871499Y1124948D03*
X872086Y1114948D03*
X871999Y1094948D03*
X872086Y1084948D03*
X860133Y1084142D03*
X845799Y1190450D03*
X849799Y1199750D03*
X846499Y1170450D03*
X897299Y1182450D03*
X887999Y1209350D03*
X871399Y1201850D03*
Y1210850D03*
Y1182850D03*
X892499Y1224550D03*
X851999Y1218550D03*
X856400Y1157700D03*
X848999Y1158050D03*
X863300Y1153800D03*
X872099Y1268150D03*
X871399Y1291450D03*
X860099Y1295450D03*
X869399Y1243850D03*
Y1229350D03*
X890499Y1285550D03*
Y1271050D03*
X892499Y1252550D03*
Y1243550D03*
X850499Y1300050D03*
Y1282550D03*
Y1268050D03*
X852499Y1249550D03*
X851999Y1237550D03*
X875399Y1322650D03*
X868499Y1392550D03*
X890999Y1336550D03*
Y1354050D03*
X841999Y1341050D03*
Y1358550D03*
X860799Y1358925D03*
X894499Y1423550D03*
Y1441050D03*
X868499Y1410050D03*
X874100Y1461600D03*
X874900Y1454000D03*
X848861Y1462463D03*
X852500Y1462600D03*
X886913Y1449010D03*
X879727Y1463696D03*
X871836Y1450460D03*
Y1435460D03*
Y1420460D03*
X914599Y1521650D03*
X910899Y1549250D03*
X894499Y1522050D03*
Y1539550D03*
X895499Y1488050D03*
X902759Y1509585D03*
X861999Y1522550D03*
X843999Y1523550D03*
X858827Y1485696D03*
X887499Y1476050D03*
X872086Y1490460D03*
X871999Y1500460D03*
Y1520460D03*
X872086Y1530460D03*
X865300Y1557700D03*
X923599Y1634350D03*
X909700Y1576400D03*
X907500Y1604000D03*
X908899Y1630050D03*
X868099Y1635650D03*
X887299Y1620050D03*
X886900Y1604100D03*
X873099Y1572550D03*
X850099Y1572250D03*
X849900Y1605100D03*
X852499Y1621350D03*
X866499Y1603050D03*
Y1612050D03*
X864000Y1578200D03*
X858400Y1561900D03*
X850499Y1562050D03*
X914899Y1657550D03*
X922599Y1682150D03*
X903599Y1686850D03*
X895999Y1661250D03*
X877699Y1646650D03*
X855799Y1658250D03*
X882999Y1678250D03*
X864099Y1683550D03*
X842799Y1701150D03*
X902900Y1709800D03*
X900500Y1721500D03*
X842500Y1799000D03*
X879399Y1798150D03*
X911299Y1800850D03*
X866699Y1770950D03*
X853799Y1790850D03*
X844499Y1788050D03*
X921549Y1788475D03*
X863099Y1813150D03*
X903299Y1814750D03*
X894999Y1829050D03*
X922899Y1853650D03*
X905299Y1852650D03*
X900299Y1876950D03*
X842199Y1879250D03*
X851500Y1821400D03*
X849375Y1824982D03*
X854905Y1825583D03*
X914999Y1887050D03*
Y1868050D03*
X854480Y1867578D03*
X849999Y1867550D03*
X863700Y1867300D03*
X865300Y1858700D03*
X862499Y1823550D03*
X854977Y1818994D03*
X887401Y1881500D03*
X894000Y1868452D03*
X887499Y1855550D03*
X869999Y1855972D03*
X871836Y1840972D03*
X869634Y1826876D03*
X914899Y1912450D03*
X916599Y1942650D03*
X897599Y1938750D03*
X914899Y1972250D03*
X873399Y1963650D03*
X904299Y1954950D03*
X897299Y1904150D03*
X907599Y1930050D03*
X915499Y1899050D03*
X861414Y1928550D03*
X843999D03*
X856999Y1970050D03*
X849999Y1970550D03*
X865200Y1968000D03*
X859314Y1891365D03*
X871921Y1905972D03*
X871421Y1895972D03*
X872086Y1925972D03*
Y1935972D03*
X879399Y1974550D03*
X850499Y1977950D03*
X868699Y1983250D03*
X921499Y1986550D03*
X901999Y1987050D03*
X864999D03*
X849499D03*
X884499Y1986550D03*
X974699Y64650D03*
X977399Y44050D03*
X954799Y17850D03*
X974699Y21450D03*
X991399Y22450D03*
X1002699Y40050D03*
X991999Y56050D03*
X941499Y6550D03*
X960999D03*
X976499D03*
X995999Y6050D03*
X967499Y47050D03*
Y56050D03*
Y64050D03*
X961499Y100050D03*
X983099Y83650D03*
X1005299Y71350D03*
X977699Y109150D03*
X994399Y101250D03*
X981099Y123450D03*
X939199Y142050D03*
X968399Y137150D03*
X967999Y73050D03*
Y82050D03*
X946899Y122550D03*
X958999Y96050D03*
X988699Y174350D03*
X967399Y180350D03*
X956099Y181350D03*
X958799Y167350D03*
X1004799Y231450D03*
X1005299Y211950D03*
Y194450D03*
Y179950D03*
X952799Y231150D03*
Y213650D03*
Y199150D03*
X982999Y203550D03*
Y221050D03*
Y189050D03*
X932499Y223550D03*
Y206050D03*
Y191550D03*
X939549Y175175D03*
X1005299Y305450D03*
Y290950D03*
X1005799Y271450D03*
X1004799Y250450D03*
X952799Y310150D03*
X953299Y290650D03*
X952299Y269650D03*
Y250650D03*
X983999Y316050D03*
Y301550D03*
X933499Y304050D03*
X983499Y280550D03*
X982499Y259550D03*
Y240550D03*
X932999Y283050D03*
X931999Y262050D03*
Y243050D03*
X1005799Y382450D03*
X1004799Y361450D03*
X1005299Y322950D03*
X1004799Y342450D03*
X952299Y380650D03*
X952799Y342150D03*
X952299Y361650D03*
X952799Y324650D03*
X984499Y393050D03*
X983499Y372050D03*
Y353050D03*
X983999Y333550D03*
X933999Y395550D03*
X932999Y374550D03*
X933499Y336050D03*
X932999Y355550D03*
X933499Y318550D03*
X966199Y473350D03*
X1000699Y482350D03*
Y463350D03*
X954799Y451650D03*
Y434150D03*
Y419650D03*
X953299Y401650D03*
X983499Y464050D03*
X983999Y427050D03*
Y444550D03*
Y412550D03*
X933499Y447050D03*
X932999Y466550D03*
X933499Y429550D03*
Y415050D03*
X966499Y552050D03*
X967199Y513350D03*
X966199Y492350D03*
X1001699Y503350D03*
X1003499Y546350D03*
X1003999Y526850D03*
X951299Y560150D03*
Y541150D03*
X951799Y521650D03*
Y504150D03*
Y489650D03*
X985999Y536550D03*
Y554050D03*
Y522050D03*
X935499Y556550D03*
Y539050D03*
Y524550D03*
X984499Y504050D03*
X983499Y483050D03*
X933999Y506550D03*
X932999Y485550D03*
X967799Y606350D03*
X966799Y585350D03*
Y566350D03*
X1005999Y636350D03*
Y618850D03*
X1004499Y586350D03*
X1005999Y604350D03*
X1003499Y565350D03*
X950299Y631650D03*
Y614150D03*
Y599650D03*
X952299Y581150D03*
X969499Y639050D03*
X986499Y613550D03*
X985499Y592550D03*
Y573550D03*
X935999Y616050D03*
X934999Y595050D03*
Y576050D03*
X949799Y670150D03*
X950799Y691150D03*
X949799Y651150D03*
X969999Y730550D03*
X968999Y709550D03*
Y690550D03*
X969499Y653550D03*
Y671050D03*
Y795750D03*
X969999Y776250D03*
Y758750D03*
Y744250D03*
X994499Y803550D03*
Y784550D03*
X994999Y747550D03*
Y765050D03*
Y733050D03*
X943999Y806050D03*
X944499Y767550D03*
X943999Y787050D03*
X944499Y750050D03*
Y735550D03*
X970499Y879750D03*
Y862250D03*
Y847750D03*
Y835750D03*
X969499Y814750D03*
X992999Y894550D03*
X993499Y857550D03*
Y875050D03*
Y843050D03*
X942999Y877550D03*
Y860050D03*
Y845550D03*
X995499Y824550D03*
X944999Y827050D03*
X965999Y954550D03*
X994499Y973550D03*
Y956050D03*
Y941550D03*
X949299Y977450D03*
X970999Y939250D03*
X969999Y918250D03*
Y899250D03*
X993999Y934550D03*
X992999Y913550D03*
X943499Y937050D03*
X942499Y916050D03*
Y897050D03*
X994999Y1033050D03*
Y1045050D03*
X993999Y1012050D03*
Y993050D03*
X948799Y1047950D03*
Y1028950D03*
X949299Y1009450D03*
Y991950D03*
X971499Y1048050D03*
X971999Y1011050D03*
Y1028550D03*
Y996550D03*
X949799Y1068950D03*
Y1080950D03*
X998599Y1128450D03*
Y1110950D03*
Y1096450D03*
X950699Y1139750D03*
Y1122250D03*
Y1107750D03*
X975999Y1115550D03*
Y1133050D03*
Y1101050D03*
X925499Y1135550D03*
Y1118050D03*
Y1103550D03*
X972499Y1088050D03*
X971499Y1067050D03*
X999099Y1214450D03*
Y1199950D03*
Y1187950D03*
X998099Y1147950D03*
Y1166950D03*
X951199Y1225750D03*
Y1211250D03*
Y1199250D03*
X950199Y1159250D03*
Y1178250D03*
X976499Y1219050D03*
Y1204550D03*
X925999Y1221550D03*
Y1207050D03*
X976499Y1192550D03*
X975499Y1171550D03*
Y1152550D03*
X925999Y1195050D03*
X924999Y1174050D03*
Y1155050D03*
X999599Y1291450D03*
X998599Y1270450D03*
Y1251450D03*
X999099Y1231950D03*
X951699Y1302750D03*
X950699Y1281750D03*
Y1262750D03*
X951199Y1243250D03*
X976999Y1296050D03*
X975999Y1275050D03*
Y1256050D03*
X976499Y1236550D03*
X926499Y1298550D03*
X925499Y1277550D03*
X925999Y1239050D03*
X925499Y1258550D03*
X975100Y1342600D03*
X1000700Y1358100D03*
X996500Y1324800D03*
X952499Y1361850D03*
X944000Y1391900D03*
X943799Y1380850D03*
Y1342950D03*
X965099Y1324350D03*
X928499Y1325350D03*
X976499Y1377050D03*
Y1362550D03*
X925999Y1379550D03*
Y1365050D03*
X992500Y1397300D03*
X964400Y1409700D03*
X946700Y1426500D03*
X994200Y1421500D03*
X924999Y1471050D03*
X926499Y1456550D03*
X925499Y1435550D03*
X925999Y1397050D03*
X925499Y1416550D03*
X973200Y1516400D03*
X972500Y1529100D03*
X966600D03*
X961400Y1528700D03*
X961900Y1522400D03*
X967100Y1522800D03*
X973000D03*
X962100Y1516000D03*
X967300Y1516400D03*
X972700Y1534800D03*
X972000Y1547500D03*
X966100D03*
X960900Y1547100D03*
X961400Y1540800D03*
X966600Y1541200D03*
X972500D03*
X961600Y1534400D03*
X966800Y1534800D03*
X972700Y1553300D03*
X961600Y1552900D03*
X966800Y1553300D03*
X944000Y1511300D03*
X943199Y1531650D03*
X924499Y1541550D03*
X924999Y1503050D03*
X924499Y1522550D03*
X924999Y1485550D03*
X972000Y1566000D03*
X966100D03*
X960900Y1565600D03*
X961400Y1559300D03*
X966600Y1559700D03*
X972500D03*
X973000Y1572800D03*
X972300Y1585500D03*
X966400D03*
X961200Y1585100D03*
X961700Y1578800D03*
X966900Y1579200D03*
X972800D03*
X961900Y1572400D03*
X967100Y1572800D03*
X972400Y1592000D03*
X966500D03*
X961300Y1591600D03*
X972200Y1598400D03*
X966300D03*
X961100Y1598000D03*
X960600Y1604300D03*
X971700Y1604700D03*
X965800D03*
X944499Y1632650D03*
X925599Y1612050D03*
X933199Y1577550D03*
X925499Y1562550D03*
X990425Y1633898D03*
X987029Y1634075D03*
X981200Y1618002D03*
X989999Y1718050D03*
X958799Y1715750D03*
X957799Y1646950D03*
X955499Y1690850D03*
X941499Y1679550D03*
X940499Y1656950D03*
X931499Y1702050D03*
X989502Y1646000D03*
X988800Y1658300D03*
X989000Y1663802D03*
X987200Y1675600D03*
X989900Y1678800D03*
X941800Y1787700D03*
X934200Y1793500D03*
X993299Y1734350D03*
X994999Y1748950D03*
X976600Y1757100D03*
X965349Y1742000D03*
X949799Y1756250D03*
X976399Y1772250D03*
X954499Y1783550D03*
X941499Y1776250D03*
X932199Y1801850D03*
X971000Y1803000D03*
X999999Y1775250D03*
X976399Y1791150D03*
X993499Y1805550D03*
X928000Y1818500D03*
X1003599Y1846650D03*
X995699Y1858950D03*
X971500Y1871500D03*
X937199Y1869950D03*
X993499Y1824550D03*
Y1833550D03*
X987999Y1971950D03*
Y1949050D03*
X1000999Y1946350D03*
X991999Y1915750D03*
X966799Y1892150D03*
X974699Y1914450D03*
X945199Y1946350D03*
X955799Y1951950D03*
X954099Y1915450D03*
X938199Y1917150D03*
X1002500Y1953500D03*
X1001599Y1921450D03*
X992299Y1929050D03*
X989999Y1962650D03*
X980999Y1933350D03*
X947499Y1936050D03*
X946199Y1966650D03*
X937499Y1893850D03*
X971499Y1956050D03*
Y1965050D03*
Y1937050D03*
X930999Y1950050D03*
X931499Y1962050D03*
X930999Y1931050D03*
X955499Y1893050D03*
Y1902050D03*
X953799Y1977950D03*
X930199Y1979550D03*
X1005000Y1980500D03*
X973999Y1986550D03*
X956499Y1986050D03*
X936999Y1986550D03*
X1022000Y15500D03*
X1013499Y6550D03*
X1010599Y115550D03*
X1007299Y432450D03*
Y414950D03*
Y400450D03*
X1016499Y1301050D03*
X1023300Y1344400D03*
X1024300Y1365200D03*
X1022599Y1322950D03*
X1024300Y1393600D03*
X1008599Y1716050D03*
X1022299Y1715750D03*
X1008999Y1702450D03*
X1016899Y1731650D03*
X1026899Y1768550D03*
X1020299Y1746650D03*
X1015299Y1765950D03*
X1009999Y1797450D03*
X1011299Y1860650D03*
X1007599Y1818450D03*
G54D18*
X78150Y28858D03*
Y178464D03*
Y434370D03*
Y583976D03*
Y839882D03*
Y989488D03*
Y1245394D03*
Y1395000D03*
Y1650906D03*
Y1800512D03*
X158071Y191614D03*
Y341220D03*
Y597126D03*
Y746732D03*
Y1002638D03*
Y1152244D03*
Y1408150D03*
Y1557756D03*
Y1813662D03*
Y1963268D03*
X886417Y191614D03*
Y341220D03*
Y597126D03*
Y746732D03*
Y1002638D03*
Y1152244D03*
Y1408150D03*
Y1557756D03*
Y1813662D03*
Y1963268D03*
G54D10*
X-39052Y28742D03*
X-43327Y310478D03*
X-39686Y917251D03*
X-38801Y1082342D03*
X-44886Y1294251D03*
X-43103Y1928864D03*
X1071932Y32074D03*
X1074813Y1348051D03*
X1076613Y1740651D03*
X1074813Y1957551D03*
G54D17*
X68898Y17047D03*
Y190275D03*
Y422559D03*
Y595787D03*
Y828071D03*
Y1001299D03*
Y1233583D03*
Y1406811D03*
Y1639095D03*
Y1812323D03*
G54D12*
X9843Y153168D03*
Y265767D03*
Y353144D03*
Y717711D03*
Y762617D03*
Y875216D03*
Y1137420D03*
Y1250019D03*
Y1337396D03*
Y1701963D03*
Y1746869D03*
Y1859468D03*
G54D23*
X1019291Y1416024D03*
Y1694212D03*
G54D11*
X11999Y53550D03*
X11499Y34050D03*
X10000Y16500D03*
X11499Y142050D03*
X11999Y69050D03*
X11302Y161500D03*
X11500Y166000D03*
X9499Y301050D03*
Y281550D03*
X8999Y318550D03*
Y889550D03*
X8499Y979050D03*
X8999Y961550D03*
Y942050D03*
Y926550D03*
X8499Y907050D03*
X8999Y1060550D03*
Y1041050D03*
Y1025550D03*
X8499Y1006050D03*
X8999Y988550D03*
X8499Y1078050D03*
X6500Y1146000D03*
X13000Y1145500D03*
Y1151000D03*
X7000Y1151500D03*
X8799Y1302550D03*
X7499Y1282050D03*
X7999Y1264550D03*
X8299Y1320050D03*
X21500Y1122500D03*
Y1092500D03*
X17500D03*
X18000Y1145500D03*
X17500Y1150500D03*
X21299Y1300250D03*
X21799Y1282750D03*
X838999Y313550D03*
X821499Y314050D03*
X863999Y313550D03*
X879200Y1698700D03*
X879900Y1709300D03*
X883900Y1709500D03*
X855350Y1703201D03*
X875900Y1709500D03*
X892700Y1727800D03*
X864000Y1748000D03*
X892700Y1736500D03*
X994999Y1986550D03*
X1020499Y50550D03*
X1020999Y33050D03*
X1020499Y122550D03*
X1020999Y105050D03*
Y85550D03*
Y70050D03*
X1021499Y141050D03*
X1020999Y230550D03*
X1021499Y213050D03*
Y193550D03*
Y178050D03*
X1020999Y158550D03*
Y304550D03*
Y289050D03*
X1020499Y269550D03*
X1020999Y252050D03*
X1020499Y341550D03*
X1020999Y324050D03*
X1020499Y391550D03*
X1020999Y374050D03*
X1020499Y463550D03*
X1020999Y446050D03*
Y426550D03*
Y411050D03*
X1021999Y558550D03*
Y539050D03*
Y523550D03*
X1021499Y504050D03*
X1021999Y486550D03*
X1021499Y576050D03*
X1020999Y642550D03*
X1020499Y623050D03*
X1020999Y605550D03*
X1020499Y695050D03*
X1020999Y677550D03*
Y658050D03*
Y720050D03*
X1020499Y809550D03*
X1020999Y792050D03*
Y772550D03*
Y757050D03*
X1020499Y737550D03*
Y880550D03*
Y865050D03*
X1019999Y845550D03*
X1020499Y828050D03*
X1019999Y917550D03*
X1020499Y900050D03*
X1019999Y971050D03*
X1019499Y951550D03*
X1019999Y934050D03*
Y986550D03*
Y1058550D03*
Y1043050D03*
X1019499Y1023550D03*
X1019999Y1006050D03*
X1020499Y1134050D03*
Y1118550D03*
X1019999Y1099050D03*
X1020499Y1081550D03*
X1019499Y1198550D03*
Y1183050D03*
X1018999Y1163550D03*
X1019499Y1146050D03*
X1016999Y1219050D03*
X1016499Y1236550D03*
X1016999Y1256050D03*
Y1271550D03*
X1022499Y1802050D03*
X1022999Y1784550D03*
Y1821550D03*
Y1837050D03*
X1020499Y1877550D03*
X1020999Y1860050D03*
Y1912550D03*
Y1897050D03*
X1017499Y1954550D03*
X1017999Y1937050D03*
Y1987050D03*
X1023000Y1973000D03*
G54D21*
X144499Y1745550D03*
X137999Y1747723D03*
X129999Y1747050D03*
X123499D03*
X117499Y1745050D03*
G54D16*
X17720Y1903144D03*
X29532Y309561D03*
Y1029522D03*
X271657Y267711D03*
Y673223D03*
Y1078734D03*
Y1484246D03*
Y1889758D03*
X994098Y149601D03*
Y673223D03*
X994099Y1068892D03*
%LPC*%
G75*
G54D24*
G01X-71137Y-139897D02*
Y-219897D01*
G01D02*
X1129963D01*
G01X-75137Y-123897D02*
G02I-12000J0D01*
G01X-80287D02*
G02I-6850J0D01*
G01X-87137Y-139897D02*
Y-107897D01*
G01X-71137Y-123897D02*
X-103137D01*
G01X-71137Y-139897D02*
X1129963D01*
G01X-71137Y-175397D02*
X1129963D01*
G01X342463Y-139897D02*
Y-219897D01*
G01X479963Y-139897D02*
Y-219897D01*
G01X594963Y-139897D02*
Y-219897D01*
G01X762463Y-139897D02*
Y-219897D01*
G01X932463Y-139897D02*
Y-219897D01*
G01X1129963Y-139897D02*
Y-219897D01*
G01X1157963Y-123897D02*
G02I-12000J0D01*
G01X1152813D02*
G02I-6850J0D01*
G01X1145963Y-139897D02*
Y-107897D01*
G01X1161963Y-123897D02*
X1129963D01*
G54D25*
G01X-89222Y-207897D02*
Y-190397D01*
G01X-80052D02*
Y-207897D01*
G01Y-199147D02*
X-89222D01*
G01X-67137Y-207897D02*
X-68447Y-207605D01*
X-69757Y-206439D01*
X-70631Y-204397D01*
X-71067Y-202064D01*
X-70631Y-199730D01*
X-69757Y-197689D01*
X-68447Y-196522D01*
X-67137Y-196231D01*
X-65827Y-196522D01*
X-64517Y-197689D01*
X-63644Y-199730D01*
X-63425Y-202064D01*
X-63644Y-204397D01*
X-64517Y-206439D01*
X-65827Y-207605D01*
X-67137Y-207897D01*
G01X-53349D02*
Y-196231D01*
G01Y-199147D02*
X-52475Y-197689D01*
X-51165Y-196522D01*
X-49419Y-196231D01*
X-47891Y-196522D01*
X-46580Y-197689D01*
X-45925Y-199730D01*
Y-207897D01*
G01X-35412Y-200022D02*
X-28425D01*
X-29080Y-197980D01*
X-30172Y-196814D01*
X-31700Y-196231D01*
X-33229Y-196522D01*
X-34539Y-197397D01*
X-35412Y-199439D01*
X-35849Y-201189D01*
Y-202939D01*
X-35412Y-204689D01*
X-34320Y-206439D01*
X-33010Y-207605D01*
X-31482Y-207897D01*
X-29954Y-207314D01*
X-28425Y-205564D01*
G01X-19222Y-213147D02*
X-17912Y-213730D01*
X-16165Y-213147D01*
X-15074Y-211981D01*
X-14200Y-210522D01*
X-12891Y-205856D01*
X-10052Y-196231D01*
G01X-17039D02*
X-12891Y-205856D01*
G01X22109Y-198564D02*
X22983Y-197689D01*
X23638Y-196231D01*
X24075Y-194188D01*
X23638Y-192439D01*
X22765Y-191272D01*
X21236Y-190397D01*
X15341D01*
Y-207897D01*
X22546D01*
X24075Y-206731D01*
X24948Y-204980D01*
X25385Y-202939D01*
X24948Y-200897D01*
X23638Y-199147D01*
X22109Y-198564D01*
X15341D01*
G01X41793Y-207897D02*
Y-196231D01*
G01Y-198272D02*
X40920Y-197106D01*
X39609Y-196522D01*
X38081Y-196231D01*
X36553Y-196814D01*
X35243Y-197980D01*
X34369Y-199730D01*
X33933Y-202064D01*
X34369Y-204397D01*
X35243Y-206147D01*
X36553Y-207314D01*
X38081Y-207897D01*
X39609Y-207605D01*
X40920Y-206731D01*
X41793Y-205564D01*
G01X59293Y-190397D02*
Y-207897D01*
G01Y-205273D02*
X58420Y-206731D01*
X57109Y-207605D01*
X55581Y-207897D01*
X53835Y-207314D01*
X52525Y-205856D01*
X51651Y-204106D01*
X51433Y-202064D01*
X51651Y-200022D01*
X52525Y-198272D01*
X53835Y-196814D01*
X55581Y-196231D01*
X57109Y-196522D01*
X58201Y-197106D01*
X59293Y-198272D01*
G01X69806Y-212272D02*
X71335Y-213439D01*
X73081Y-213730D01*
X74609Y-213439D01*
X75920Y-211981D01*
X76793Y-209939D01*
Y-196231D01*
G01Y-198564D02*
X75920Y-197397D01*
X74609Y-196522D01*
X73081Y-196231D01*
X71335Y-196814D01*
X70243Y-197980D01*
X69369Y-200022D01*
X68933Y-202064D01*
X69151Y-203814D01*
X70025Y-205856D01*
X71335Y-207314D01*
X73081Y-207897D01*
X74391Y-207605D01*
X75920Y-206439D01*
X76793Y-205273D01*
G01X87088Y-200022D02*
X94075D01*
X93420Y-197980D01*
X92328Y-196814D01*
X90800Y-196231D01*
X89271Y-196522D01*
X87961Y-197397D01*
X87088Y-199439D01*
X86651Y-201189D01*
Y-202939D01*
X87088Y-204689D01*
X88180Y-206439D01*
X89490Y-207605D01*
X91018Y-207897D01*
X92546Y-207314D01*
X94075Y-205564D01*
G01X104806Y-207897D02*
Y-196231D01*
G01Y-198564D02*
X105898Y-197397D01*
X106990Y-196522D01*
X108518Y-196231D01*
X109609Y-196522D01*
X110920Y-197397D01*
G01X138060Y-207897D02*
Y-190397D01*
X142426D01*
X144173Y-191272D01*
X145483Y-192439D01*
X146575Y-194188D01*
X147448Y-196231D01*
X147666Y-199147D01*
X147448Y-202064D01*
X146575Y-204106D01*
X145483Y-205856D01*
X144173Y-207022D01*
X142426Y-207897D01*
X138060D01*
G01X155996D02*
Y-190397D01*
X161236D01*
X162983Y-191272D01*
X164293Y-193314D01*
X164730Y-195647D01*
X164293Y-197980D01*
X163201Y-199730D01*
X161236Y-200606D01*
X155996D01*
G01X179609Y-198564D02*
X180483Y-197689D01*
X181138Y-196231D01*
X181575Y-194188D01*
X181138Y-192439D01*
X180265Y-191272D01*
X178736Y-190397D01*
X172841D01*
Y-207897D01*
X180046D01*
X181575Y-206731D01*
X182448Y-204980D01*
X182885Y-202939D01*
X182448Y-200897D01*
X181138Y-199147D01*
X179609Y-198564D01*
X172841D01*
G01X208496Y-190397D02*
Y-207897D01*
X217230D01*
G01X230363D02*
X229053Y-207605D01*
X227743Y-206439D01*
X226869Y-204397D01*
X226433Y-202064D01*
X226869Y-199730D01*
X227743Y-197689D01*
X229053Y-196522D01*
X230363Y-196231D01*
X231673Y-196522D01*
X232983Y-197689D01*
X233856Y-199730D01*
X234075Y-202064D01*
X233856Y-204397D01*
X232983Y-206439D01*
X231673Y-207605D01*
X230363Y-207897D01*
G01X242404Y-196231D02*
X245025Y-207897D01*
X247863Y-196231D01*
X250701Y-207897D01*
X253322Y-196231D01*
G01X278496Y-190397D02*
Y-207897D01*
X287230D01*
G01X300363D02*
X299053Y-207605D01*
X297743Y-206439D01*
X296869Y-204397D01*
X296433Y-202064D01*
X296869Y-199730D01*
X297743Y-197689D01*
X299053Y-196522D01*
X300363Y-196231D01*
X301673Y-196522D01*
X302983Y-197689D01*
X303856Y-199730D01*
X304075Y-202064D01*
X303856Y-204397D01*
X302983Y-206439D01*
X301673Y-207605D01*
X300363Y-207897D01*
G01X314588Y-205856D02*
X315680Y-207022D01*
X317208Y-207897D01*
X318518D01*
X319828Y-207314D01*
X320701Y-206439D01*
X321138Y-205273D01*
X320920Y-203522D01*
X320046Y-202647D01*
X316116Y-200897D01*
X315243Y-198855D01*
X315680Y-197397D01*
X316553Y-196522D01*
X317863Y-196231D01*
X319173Y-196522D01*
X320483Y-197397D01*
G01X332088Y-205856D02*
X333180Y-207022D01*
X334708Y-207897D01*
X336018D01*
X337328Y-207314D01*
X338201Y-206439D01*
X338638Y-205273D01*
X338420Y-203522D01*
X337546Y-202647D01*
X333616Y-200897D01*
X332743Y-198855D01*
X333180Y-197397D01*
X334053Y-196522D01*
X335363Y-196231D01*
X336673Y-196522D01*
X337983Y-197397D01*
G01X94686Y-164897D02*
Y-147397D01*
X100363Y-161980D01*
X106040Y-147397D01*
Y-164897D01*
G01X117863D02*
X116553Y-164605D01*
X115243Y-163439D01*
X114369Y-161397D01*
X113933Y-159064D01*
X114369Y-156730D01*
X115243Y-154689D01*
X116553Y-153522D01*
X117863Y-153231D01*
X119173Y-153522D01*
X120483Y-154689D01*
X121356Y-156730D01*
X121575Y-159064D01*
X121356Y-161397D01*
X120483Y-163439D01*
X119173Y-164605D01*
X117863Y-164897D01*
G01X139293Y-147397D02*
Y-164897D01*
G01Y-162273D02*
X138420Y-163731D01*
X137109Y-164605D01*
X135581Y-164897D01*
X133835Y-164314D01*
X132525Y-162856D01*
X131651Y-161106D01*
X131433Y-159064D01*
X131651Y-157022D01*
X132525Y-155272D01*
X133835Y-153814D01*
X135581Y-153231D01*
X137109Y-153522D01*
X138201Y-154106D01*
X139293Y-155272D01*
G01X149588Y-157022D02*
X156575D01*
X155920Y-154980D01*
X154828Y-153814D01*
X153300Y-153231D01*
X151771Y-153522D01*
X150461Y-154397D01*
X149588Y-156439D01*
X149151Y-158189D01*
Y-159939D01*
X149588Y-161689D01*
X150680Y-163439D01*
X151990Y-164605D01*
X153518Y-164897D01*
X155046Y-164314D01*
X156575Y-162564D01*
G01X170363Y-164897D02*
Y-147397D01*
G01X376163Y-209897D02*
Y-192397D01*
X373543Y-195897D01*
G01Y-209897D02*
X378783D01*
G01X396283D02*
Y-192397D01*
X388204Y-204939D01*
X399122D01*
G01X406360Y-207273D02*
X407669Y-208731D01*
X409198Y-209605D01*
X411163Y-209897D01*
X413128Y-209314D01*
X414656Y-208147D01*
X415748Y-206106D01*
X415966Y-203772D01*
X415530Y-201439D01*
X414438Y-199980D01*
X412909Y-198814D01*
X411381Y-198522D01*
X409853Y-198814D01*
X407888Y-199980D01*
X408543Y-192397D01*
X414438D01*
G01X431283Y-209897D02*
Y-192397D01*
X423204Y-204939D01*
X434122D01*
G01X441360Y-207273D02*
X442669Y-208731D01*
X444198Y-209605D01*
X446163Y-209897D01*
X448128Y-209314D01*
X449656Y-208147D01*
X450748Y-206106D01*
X450966Y-203772D01*
X450530Y-201439D01*
X449438Y-199980D01*
X447909Y-198814D01*
X446381Y-198522D01*
X444853Y-198814D01*
X442888Y-199980D01*
X443543Y-192397D01*
X449438D01*
G01X363046Y-164897D02*
Y-147397D01*
X368286D01*
X370033Y-148272D01*
X371343Y-150314D01*
X371780Y-152647D01*
X371343Y-154980D01*
X370251Y-156730D01*
X368286Y-157606D01*
X363046D01*
G01X389716Y-148856D02*
X388406Y-147980D01*
X386878Y-147397D01*
X385131D01*
X383166Y-148272D01*
X381638Y-149730D01*
X380546Y-151481D01*
X379673Y-154397D01*
X379454Y-157022D01*
X379891Y-159647D01*
X380546Y-161397D01*
X381856Y-163147D01*
X383385Y-164314D01*
X384913Y-164897D01*
X386441D01*
X387970Y-164314D01*
X389280Y-163439D01*
X390372Y-162273D01*
G01X404159Y-155564D02*
X405033Y-154689D01*
X405688Y-153231D01*
X406125Y-151188D01*
X405688Y-149439D01*
X404815Y-148272D01*
X403286Y-147397D01*
X397391D01*
Y-164897D01*
X404596D01*
X406125Y-163731D01*
X406998Y-161980D01*
X407435Y-159939D01*
X406998Y-157897D01*
X405688Y-156147D01*
X404159Y-155564D01*
X397391D01*
G01X413363Y-170730D02*
X426463D01*
G01X432391Y-164897D02*
Y-147397D01*
X442435Y-164897D01*
Y-147397D01*
G01X454913Y-164897D02*
X453166Y-164605D01*
X451638Y-163439D01*
X450328Y-161689D01*
X449454Y-159647D01*
X449018Y-157314D01*
Y-154980D01*
X449454Y-152647D01*
X450328Y-150605D01*
X451638Y-148856D01*
X453166Y-147689D01*
X454913Y-147397D01*
X456659Y-147689D01*
X458188Y-148856D01*
X459498Y-150605D01*
X460372Y-152647D01*
X460808Y-154980D01*
Y-157314D01*
X460372Y-159647D01*
X459498Y-161689D01*
X458188Y-163439D01*
X456659Y-164605D01*
X454913Y-164897D01*
G01X505754Y-147397D02*
X511213Y-164897D01*
X516672Y-147397D01*
G01X533080Y-164897D02*
X524346D01*
Y-147397D01*
X533080D01*
G01X529586Y-155855D02*
X524346D01*
G01X541846Y-164897D02*
Y-147397D01*
X547305D01*
X549051Y-148272D01*
X550143Y-149439D01*
X550580Y-151772D01*
X550143Y-154106D01*
X548833Y-155564D01*
X547305Y-156439D01*
X541846D01*
G01X547305D02*
X550580Y-164897D01*
G01X563713Y-165480D02*
X563276Y-165189D01*
Y-164605D01*
X563713Y-164314D01*
X564150Y-164605D01*
Y-165189D01*
X563713Y-165480D01*
G01X524128Y-207564D02*
X525875Y-209022D01*
X527840Y-209897D01*
X529586D01*
X531333Y-209022D01*
X532643Y-207564D01*
X533298Y-205522D01*
X532861Y-203481D01*
X531770Y-201730D01*
X529805Y-200564D01*
X527185Y-199980D01*
X525656Y-198814D01*
X525001Y-196772D01*
X525438Y-194730D01*
X526530Y-193272D01*
X528058Y-192397D01*
X529586D01*
X531115Y-192980D01*
X532425Y-194439D01*
G01X540754Y-209897D02*
X546213Y-192397D01*
X551672Y-209897D01*
G01X549706Y-203772D02*
X542719D01*
G01X639296Y-192397D02*
Y-209897D01*
X648030D01*
G01X657015Y-195314D02*
X658325Y-193564D01*
X659853Y-192689D01*
X661600Y-192397D01*
X663783Y-192980D01*
X665311Y-194439D01*
X665748Y-196188D01*
X665530Y-197939D01*
X664656Y-199397D01*
X660290Y-202314D01*
X658325Y-204355D01*
X657015Y-207273D01*
X656578Y-209897D01*
X665748D01*
G01X679973Y-201147D02*
X684340D01*
Y-206397D01*
X683030Y-208147D01*
X681501Y-209314D01*
X679318Y-209897D01*
X677135Y-209314D01*
X675606Y-208147D01*
X674296Y-206397D01*
X673423Y-204355D01*
X672986Y-202022D01*
Y-199980D01*
X673423Y-198231D01*
X674296Y-196188D01*
X675606Y-194439D01*
X676916Y-193272D01*
X678663Y-192397D01*
X680191D01*
X681938Y-192980D01*
X683248Y-194147D01*
G01X691141Y-209897D02*
Y-192397D01*
X701185Y-209897D01*
Y-192397D01*
G01X708860Y-209897D02*
Y-192397D01*
X713226D01*
X714973Y-193272D01*
X716283Y-194439D01*
X717375Y-196188D01*
X718248Y-198231D01*
X718466Y-201147D01*
X718248Y-204064D01*
X717375Y-206106D01*
X716283Y-207856D01*
X714973Y-209022D01*
X713226Y-209897D01*
X708860D01*
G01X630546Y-147397D02*
Y-164897D01*
X639280D01*
G01X656343D02*
Y-153231D01*
G01Y-155272D02*
X655470Y-154106D01*
X654159Y-153522D01*
X652631Y-153231D01*
X651103Y-153814D01*
X649793Y-154980D01*
X648919Y-156730D01*
X648483Y-159064D01*
X648919Y-161397D01*
X649793Y-163147D01*
X651103Y-164314D01*
X652631Y-164897D01*
X654159Y-164605D01*
X655470Y-163731D01*
X656343Y-162564D01*
G01X665328Y-170147D02*
X666638Y-170730D01*
X668385Y-170147D01*
X669476Y-168981D01*
X670350Y-167522D01*
X671659Y-162856D01*
X674498Y-153231D01*
G01X667511D02*
X671659Y-162856D01*
G01X684138Y-157022D02*
X691125D01*
X690470Y-154980D01*
X689378Y-153814D01*
X687850Y-153231D01*
X686321Y-153522D01*
X685011Y-154397D01*
X684138Y-156439D01*
X683701Y-158189D01*
Y-159939D01*
X684138Y-161689D01*
X685230Y-163439D01*
X686540Y-164605D01*
X688068Y-164897D01*
X689596Y-164314D01*
X691125Y-162564D01*
G01X701856Y-164897D02*
Y-153231D01*
G01Y-155564D02*
X702948Y-154397D01*
X704040Y-153522D01*
X705568Y-153231D01*
X706659Y-153522D01*
X707970Y-154397D01*
G01X719138Y-162856D02*
X720230Y-164022D01*
X721758Y-164897D01*
X723068D01*
X724378Y-164314D01*
X725251Y-163439D01*
X725688Y-162273D01*
X725470Y-160522D01*
X724596Y-159647D01*
X720666Y-157897D01*
X719793Y-155855D01*
X720230Y-154397D01*
X721103Y-153522D01*
X722413Y-153231D01*
X723723Y-153522D01*
X725033Y-154397D01*
G01X790596Y-209897D02*
Y-192397D01*
X796055D01*
X797801Y-193272D01*
X798893Y-194439D01*
X799330Y-196772D01*
X798893Y-199106D01*
X797583Y-200564D01*
X796055Y-201439D01*
X790596D01*
G01X796055D02*
X799330Y-209897D01*
G01X809188Y-202022D02*
X816175D01*
X815520Y-199980D01*
X814428Y-198814D01*
X812900Y-198231D01*
X811371Y-198522D01*
X810061Y-199397D01*
X809188Y-201439D01*
X808751Y-203189D01*
Y-204939D01*
X809188Y-206689D01*
X810280Y-208439D01*
X811590Y-209605D01*
X813118Y-209897D01*
X814646Y-209314D01*
X816175Y-207564D01*
G01X826033Y-209897D02*
Y-192397D01*
G01Y-201147D02*
X827125Y-199397D01*
X828435Y-198522D01*
X829745Y-198231D01*
X831709Y-198814D01*
X833020Y-199980D01*
X833893Y-202022D01*
Y-204355D01*
X833456Y-206689D01*
X832583Y-208439D01*
X831055Y-209605D01*
X829745Y-209897D01*
X828435Y-209605D01*
X827125Y-208731D01*
X826033Y-207273D01*
G01X844188Y-202022D02*
X851175D01*
X850520Y-199980D01*
X849428Y-198814D01*
X847900Y-198231D01*
X846371Y-198522D01*
X845061Y-199397D01*
X844188Y-201439D01*
X843751Y-203189D01*
Y-204939D01*
X844188Y-206689D01*
X845280Y-208439D01*
X846590Y-209605D01*
X848118Y-209897D01*
X849646Y-209314D01*
X851175Y-207564D01*
G01X868456Y-199689D02*
X866928Y-198522D01*
X865618Y-198231D01*
X863871Y-198814D01*
X862561Y-199980D01*
X861688Y-202022D01*
X861469Y-204064D01*
X861688Y-206106D01*
X862561Y-207856D01*
X863871Y-209314D01*
X865618Y-209897D01*
X867146Y-209314D01*
X868456Y-208147D01*
G01X885956Y-199689D02*
X884428Y-198522D01*
X883118Y-198231D01*
X881371Y-198814D01*
X880061Y-199980D01*
X879188Y-202022D01*
X878969Y-204064D01*
X879188Y-206106D01*
X880061Y-207856D01*
X881371Y-209314D01*
X883118Y-209897D01*
X884646Y-209314D01*
X885956Y-208147D01*
G01X903893Y-209897D02*
Y-198231D01*
G01Y-200272D02*
X903020Y-199106D01*
X901709Y-198522D01*
X900181Y-198231D01*
X898653Y-198814D01*
X897343Y-199980D01*
X896469Y-201730D01*
X896033Y-204064D01*
X896469Y-206397D01*
X897343Y-208147D01*
X898653Y-209314D01*
X900181Y-209897D01*
X901709Y-209605D01*
X903020Y-208731D01*
X903893Y-207564D01*
G01X781410Y-164897D02*
Y-147397D01*
X785776D01*
X787523Y-148272D01*
X788833Y-149439D01*
X789925Y-151188D01*
X790798Y-153231D01*
X791016Y-156147D01*
X790798Y-159064D01*
X789925Y-161106D01*
X788833Y-162856D01*
X787523Y-164022D01*
X785776Y-164897D01*
X781410D01*
G01X800438Y-157022D02*
X807425D01*
X806770Y-154980D01*
X805678Y-153814D01*
X804150Y-153231D01*
X802621Y-153522D01*
X801311Y-154397D01*
X800438Y-156439D01*
X800001Y-158189D01*
Y-159939D01*
X800438Y-161689D01*
X801530Y-163439D01*
X802840Y-164605D01*
X804368Y-164897D01*
X805896Y-164314D01*
X807425Y-162564D01*
G01X817938Y-162856D02*
X819030Y-164022D01*
X820558Y-164897D01*
X821868D01*
X823178Y-164314D01*
X824051Y-163439D01*
X824488Y-162273D01*
X824270Y-160522D01*
X823396Y-159647D01*
X819466Y-157897D01*
X818593Y-155855D01*
X819030Y-154397D01*
X819903Y-153522D01*
X821213Y-153231D01*
X822523Y-153522D01*
X823833Y-154397D01*
G01X838713Y-153231D02*
Y-164897D01*
G01Y-148564D02*
X838276Y-148272D01*
Y-147689D01*
X838713Y-147397D01*
X839150Y-147689D01*
Y-148272D01*
X838713Y-148564D01*
G01X853156Y-169272D02*
X854685Y-170439D01*
X856431Y-170730D01*
X857959Y-170439D01*
X859270Y-168981D01*
X860143Y-166939D01*
Y-153231D01*
G01Y-155564D02*
X859270Y-154397D01*
X857959Y-153522D01*
X856431Y-153231D01*
X854685Y-153814D01*
X853593Y-154980D01*
X852719Y-157022D01*
X852283Y-159064D01*
X852501Y-160814D01*
X853375Y-162856D01*
X854685Y-164314D01*
X856431Y-164897D01*
X857741Y-164605D01*
X859270Y-163439D01*
X860143Y-162273D01*
G01X870001Y-164897D02*
Y-153231D01*
G01Y-156147D02*
X870875Y-154689D01*
X872185Y-153522D01*
X873931Y-153231D01*
X875459Y-153522D01*
X876770Y-154689D01*
X877425Y-156730D01*
Y-164897D01*
G01X887938Y-157022D02*
X894925D01*
X894270Y-154980D01*
X893178Y-153814D01*
X891650Y-153231D01*
X890121Y-153522D01*
X888811Y-154397D01*
X887938Y-156439D01*
X887501Y-158189D01*
Y-159939D01*
X887938Y-161689D01*
X889030Y-163439D01*
X890340Y-164605D01*
X891868Y-164897D01*
X893396Y-164314D01*
X894925Y-162564D01*
G01X905656Y-164897D02*
Y-153231D01*
G01Y-155564D02*
X906748Y-154397D01*
X907840Y-153522D01*
X909368Y-153231D01*
X910459Y-153522D01*
X911770Y-154397D01*
G01X952413Y-192397D02*
X950666Y-192980D01*
X949356Y-194439D01*
X948483Y-196188D01*
X947828Y-198522D01*
X947610Y-201147D01*
X947828Y-203772D01*
X948483Y-206106D01*
X949356Y-207856D01*
X950666Y-209314D01*
X952413Y-209897D01*
X954159Y-209314D01*
X955470Y-207856D01*
X956343Y-206106D01*
X956998Y-203772D01*
X957216Y-201147D01*
X956998Y-198522D01*
X956343Y-196188D01*
X955470Y-194439D01*
X954159Y-192980D01*
X952413Y-192397D01*
G01X969913Y-209897D02*
X971441Y-209605D01*
X973188Y-208731D01*
X974280Y-207273D01*
X974716Y-205230D01*
X974280Y-203189D01*
X972970Y-201439D01*
X971005Y-200564D01*
X968821D01*
X967511Y-199980D01*
X966419Y-198522D01*
X965983Y-196481D01*
X966638Y-194439D01*
X968166Y-192980D01*
X969913Y-192397D01*
X971659Y-192980D01*
X973188Y-194439D01*
X973843Y-196481D01*
X973406Y-198522D01*
X972315Y-199980D01*
X971005Y-200564D01*
X968821D01*
X966856Y-201439D01*
X965546Y-203189D01*
X965110Y-205230D01*
X965546Y-207273D01*
X966638Y-208731D01*
X968385Y-209605D01*
X969913Y-209897D01*
G01X983483Y-210480D02*
X991343Y-192397D01*
G01X1004913D02*
X1003166Y-192980D01*
X1001856Y-194439D01*
X1000983Y-196188D01*
X1000328Y-198522D01*
X1000110Y-201147D01*
X1000328Y-203772D01*
X1000983Y-206106D01*
X1001856Y-207856D01*
X1003166Y-209314D01*
X1004913Y-209897D01*
X1006659Y-209314D01*
X1007970Y-207856D01*
X1008843Y-206106D01*
X1009498Y-203772D01*
X1009716Y-201147D01*
X1009498Y-198522D01*
X1008843Y-196188D01*
X1007970Y-194439D01*
X1006659Y-192980D01*
X1004913Y-192397D01*
G01X1022413Y-209897D02*
Y-192397D01*
X1019793Y-195897D01*
G01Y-209897D02*
X1025033D01*
G01X1035983Y-210480D02*
X1043843Y-192397D01*
G01X1053265Y-195314D02*
X1054575Y-193564D01*
X1056103Y-192689D01*
X1057850Y-192397D01*
X1060033Y-192980D01*
X1061561Y-194439D01*
X1061998Y-196188D01*
X1061780Y-197939D01*
X1060906Y-199397D01*
X1056540Y-202314D01*
X1054575Y-204355D01*
X1053265Y-207273D01*
X1052828Y-209897D01*
X1061998D01*
G01X1074913Y-192397D02*
X1073166Y-192980D01*
X1071856Y-194439D01*
X1070983Y-196188D01*
X1070328Y-198522D01*
X1070110Y-201147D01*
X1070328Y-203772D01*
X1070983Y-206106D01*
X1071856Y-207856D01*
X1073166Y-209314D01*
X1074913Y-209897D01*
X1076659Y-209314D01*
X1077970Y-207856D01*
X1078843Y-206106D01*
X1079498Y-203772D01*
X1079716Y-201147D01*
X1079498Y-198522D01*
X1078843Y-196188D01*
X1077970Y-194439D01*
X1076659Y-192980D01*
X1074913Y-192397D01*
G01X1092413Y-209897D02*
Y-192397D01*
X1089793Y-195897D01*
G01Y-209897D02*
X1095033D01*
G01X1112533D02*
Y-192397D01*
X1104454Y-204939D01*
X1115372D01*
G01X1000110Y-164897D02*
Y-147397D01*
X1004476D01*
X1006223Y-148272D01*
X1007533Y-149439D01*
X1008625Y-151188D01*
X1009498Y-153231D01*
X1009716Y-156147D01*
X1009498Y-159064D01*
X1008625Y-161106D01*
X1007533Y-162856D01*
X1006223Y-164022D01*
X1004476Y-164897D01*
X1000110D01*
G01X1026343D02*
Y-153231D01*
G01Y-155272D02*
X1025470Y-154106D01*
X1024159Y-153522D01*
X1022631Y-153231D01*
X1021103Y-153814D01*
X1019793Y-154980D01*
X1018919Y-156730D01*
X1018483Y-159064D01*
X1018919Y-161397D01*
X1019793Y-163147D01*
X1021103Y-164314D01*
X1022631Y-164897D01*
X1024159Y-164605D01*
X1025470Y-163731D01*
X1026343Y-162564D01*
G01X1039913Y-147397D02*
Y-164897D01*
G01X1036856Y-153231D02*
X1042970D01*
G01X1054138Y-157022D02*
X1061125D01*
X1060470Y-154980D01*
X1059378Y-153814D01*
X1057850Y-153231D01*
X1056321Y-153522D01*
X1055011Y-154397D01*
X1054138Y-156439D01*
X1053701Y-158189D01*
Y-159939D01*
X1054138Y-161689D01*
X1055230Y-163439D01*
X1056540Y-164605D01*
X1058068Y-164897D01*
X1059596Y-164314D01*
X1061125Y-162564D01*
M02*
